FILE_TYPE = MACRO_DRAWING;
SET COLOR_WIRE YELLOW;
SET COLOR_PROP MONO;
SET COLOR_DOT WHITE;
SET COLOR_ARC YELLOW;
SET COLOR_BODY GREEN;
SET COLOR_NOTE MONO;
SET PROP_DISPLAY VALUE;
SET PAGE_NUMBER P208;
FORCEADD OFFPAGE..2
(-975 4800);
FORCEPROP 2 LAST $XR0 206 
J 0
(-786 4800);
DISPLAY 0.638298 (-786 4800);
PAINT MONO (-786 4800);
FORCEPROP 1 LAST COMMENT_BODY TRUE
J 0
(-1020 4705);
DISPLAY 1.723404 (-1020 4705);
PAINT GREEN (-1020 4705);
DISPLAY INVISIBLE (-1020 4705);
FORCEPROP 1 LAST OFFPAGE TRUE
J 0
(-650 4675);
DISPLAY 1.723404 (-650 4675);
PAINT GREEN (-650 4675);
DISPLAY INVISIBLE (-650 4675);
FORCEPROP 2 LAST CDS_LIB mstr_standard
J 2
(-975 4800);
DISPLAY 1.936170 (-975 4800);
PAINT ORANGE (-975 4800);
DISPLAY INVISIBLE (-975 4800);
FORCEPROP 2 LAST BOM_COST PROC_VRD_VCCIN_CPU0
J 0
(-775 4850);
DISPLAY 1.446809 (-775 4850);
PAINT MONO (-775 4850);
DISPLAY INVISIBLE (-775 4850);
FORCEPROP 2 LAST PATH I1
J 0
(-770 4850);
DISPLAY 1.021277 (-770 4850);
PAINT ORANGE (-770 4850);
DISPLAY INVISIBLE (-770 4850);
FORCEPROP 2 LAST ROOM PVCCIN_CPU1_PWR_VR
J 0
(-1375 4875);
DISPLAY 1.936170 (-1375 4875);
PAINT ORANGE (-1375 4875);
DISPLAY INVISIBLE (-1375 4875);
FORCEADD GND..1
(-400 3075);
FORCEPROP 3 LASTPIN (-400 3125) SIG_NAME GND\g
J 0
(-390 3135);
DISPLAY 0.659574 (-390 3135);
PAINT MONO (-390 3135);
DISPLAY INVISIBLE (-390 3135);
FORCEPROP 2 LAST ROOM PVCCIN_CPU1_PWR_VR
J 0
(-950 3150);
DISPLAY 1.936170 (-950 3150);
PAINT ORANGE (-950 3150);
DISPLAY INVISIBLE (-950 3150);
FORCEPROP 2 LAST BOM_COST PROC_VRD_VCCIN_CPU0
J 0
(-775 3150);
DISPLAY 1.446809 (-775 3150);
PAINT MONO (-775 3150);
DISPLAY INVISIBLE (-775 3150);
FORCEPROP 1 LAST SIZE 1B
J 0
(-325 3025);
DISPLAY 1.723404 (-325 3025);
PAINT GREEN (-325 3025);
DISPLAY INVISIBLE (-325 3025);
FORCEPROP 2 LAST CDS_LIB mstr_symbols
J 0
(-400 3075);
DISPLAY 1.936170 (-400 3075);
PAINT ORANGE (-400 3075);
DISPLAY INVISIBLE (-400 3075);
FORCEPROP 1 LAST VOLTAGE 0
J 0
(-400 3075);
PAINT SKYBLUE (-400 3075);
DISPLAY INVISIBLE (-400 3075);
FORCEPROP 1 LAST PATH I10
J 0
(-325 3075);
DISPLAY 0.872340 (-325 3075);
PAINT AQUA (-325 3075);
DISPLAY INVISIBLE (-325 3075);
FORCEPROP 1 LAST BODY_TYPE PLUMBING
J 0
(-445 3032);
DISPLAY 0.340426 (-445 3032);
PAINT GREEN (-445 3032);
DISPLAY INVISIBLE (-445 3032);
FORCEPROP 1 LAST HDL_POWER GND
J 0
(-400 3225);
DISPLAY 1.723404 (-400 3225);
PAINT GREEN (-400 3225);
DISPLAY INVISIBLE (-400 3225);
FORCEADD CAP..1
(-2225 3500);
FORCEPROP 1 LAST PART_NUMBER A36096-046
J 0
(-2025 3575);
DISPLAY 0.617021 (-2025 3575);
PAINT BLUE (-2025 3575);
FORCEPROP 1 LAST VALUE 1000PF
J 0
(-2175 3550);
DISPLAY 0.617021 (-2175 3550);
PAINT SKYBLUE (-2175 3550);
FORCEPROP 1 LAST VOLTAGE 50V
J 0
(-2175 3500);
DISPLAY 0.617021 (-2175 3500);
PAINT SKYBLUE (-2175 3500);
FORCEPROP 1 LAST TOLERANCE 10%
J 0
(-2175 3450);
DISPLAY 0.617021 (-2175 3450);
PAINT SKYBLUE (-2175 3450);
FORCEPROP 1 LASTPIN (-2225 3400) $PN 2
J 0
(-2215 3380);
DISPLAY 0.787234 (-2215 3380);
PAINT ORANGE (-2215 3380);
FORCEPROP 0 LAST POP NOPOP
J 0
(-2025 3475);
DISPLAY 0.808511 (-2025 3475);
PAINT RED (-2025 3475);
FORCEPROP 1 LAST PACK_TYPE 0402LF
J 0
(-1925 3525);
DISPLAY 0.617021 (-1925 3525);
PAINT SKYBLUE (-1925 3525);
FORCEPROP 1 LAST MATERIAL X7R
J 0
(-2025 3525);
DISPLAY 0.617021 (-2025 3525);
PAINT SKYBLUE (-2025 3525);
FORCEPROP 1 LAST LOCATION CT18
J 0
(-2175 3600);
DISPLAY 0.617021 (-2175 3600);
PAINT AQUA (-2175 3600);
FORCEPROP 1 LASTPIN (-2225 3600) $PN 1
J 0
(-2215 3580);
DISPLAY 0.787234 (-2215 3580);
PAINT ORANGE (-2215 3580);
FORCEPROP 2 LAST CDS_LIB mstr_discrete
J 0
(-2225 3500);
PAINT MONO (-2225 3500);
DISPLAY INVISIBLE (-2225 3500);
FORCEPROP 1 LAST PATH I104
J 0
(-2175 3650);
DISPLAY 0.978723 (-2175 3650);
PAINT WHITE (-2175 3650);
DISPLAY INVISIBLE (-2175 3650);
FORCEPROP 0 LAST ROOM VDDQ_KLM_PWR_VR
J 0
(-2175 3700);
DISPLAY 1.021277 (-2175 3700);
PAINT ORANGE (-2175 3700);
DISPLAY INVISIBLE (-2175 3700);
FORCEPROP 0 LAST SEC 1
J 0
(-2175 3650);
DISPLAY 0.680851 (-2175 3650);
PAINT MONO (-2175 3650);
DISPLAY INVISIBLE (-2175 3650);
FORCEPROP 2 LAST SEC_TYPE 0402LF
J 0
(-2175 3700);
DISPLAY 1.021277 (-2175 3700);
PAINT ORANGE (-2175 3700);
DISPLAY INVISIBLE (-2175 3700);
FORCEADD CAP..1
(-2075 875);
FORCEPROP 0 LAST POP NOPOP
J 0
(-2000 825);
DISPLAY 0.808511 (-2000 825);
PAINT RED (-2000 825);
FORCEPROP 1 LAST TOLERANCE 10%
J 0
(-1925 875);
DISPLAY 0.617021 (-1925 875);
PAINT SKYBLUE (-1925 875);
FORCEPROP 1 LAST PART_NUMBER A36096-046
J 0
(-1900 975);
DISPLAY 0.617021 (-1900 975);
PAINT BLUE (-1900 975);
FORCEPROP 1 LAST MATERIAL X7R
J 0
(-1850 925);
DISPLAY 0.617021 (-1850 925);
PAINT SKYBLUE (-1850 925);
FORCEPROP 1 LASTPIN (-2075 975) $PN 1
J 0
(-2065 955);
DISPLAY 0.787234 (-2065 955);
PAINT ORANGE (-2065 955);
FORCEPROP 1 LAST LOCATION CT20
J 0
(-2025 975);
DISPLAY 0.617021 (-2025 975);
PAINT AQUA (-2025 975);
FORCEPROP 1 LAST VALUE 1000PF
J 0
(-2025 925);
DISPLAY 0.617021 (-2025 925);
PAINT SKYBLUE (-2025 925);
FORCEPROP 1 LAST VOLTAGE 50V
J 0
(-2025 875);
DISPLAY 0.617021 (-2025 875);
PAINT SKYBLUE (-2025 875);
FORCEPROP 1 LAST PACK_TYPE 0402LF
J 0
(-1800 875);
DISPLAY 0.617021 (-1800 875);
PAINT SKYBLUE (-1800 875);
FORCEPROP 1 LASTPIN (-2075 775) $PN 2
J 0
(-2065 805);
DISPLAY 0.787234 (-2065 805);
PAINT ORANGE (-2065 805);
FORCEPROP 2 LAST CDS_LIB mstr_discrete
J 0
(-2075 875);
PAINT MONO (-2075 875);
DISPLAY INVISIBLE (-2075 875);
FORCEPROP 1 LAST PATH I105
J 0
(-2025 1025);
DISPLAY 0.978723 (-2025 1025);
PAINT WHITE (-2025 1025);
DISPLAY INVISIBLE (-2025 1025);
FORCEPROP 0 LAST ROOM VDDQ_KLM_PWR_VR
J 0
(-2025 1075);
DISPLAY 1.021277 (-2025 1075);
PAINT ORANGE (-2025 1075);
DISPLAY INVISIBLE (-2025 1075);
FORCEPROP 0 LAST SEC 1
J 0
(-2025 1025);
DISPLAY 0.680851 (-2025 1025);
PAINT MONO (-2025 1025);
DISPLAY INVISIBLE (-2025 1025);
FORCEPROP 2 LAST SEC_TYPE 0402LF
J 0
(-2025 1075);
DISPLAY 1.021277 (-2025 1075);
PAINT ORANGE (-2025 1075);
DISPLAY INVISIBLE (-2025 1075);
FORCEADD RES..1
(-4975 3700);
FORCEPROP 1 LAST LOCATION RT11
J 0
(-5150 3600);
DISPLAY 0.617021 (-5150 3600);
PAINT AQUA (-5150 3600);
FORCEPROP 1 LAST VALUE 0
J 2
(-5025 3650);
DISPLAY 0.617021 (-5025 3650);
PAINT SKYBLUE (-5025 3650);
FORCEPROP 1 LAST MATERIAL CHIP
J 0
(-4975 3550);
DISPLAY 0.617021 (-4975 3550);
PAINT SKYBLUE (-4975 3550);
FORCEPROP 1 LAST WATTAGE 1/10W
J 2
(-5000 3550);
DISPLAY 0.617021 (-5000 3550);
PAINT SKYBLUE (-5000 3550);
FORCEPROP 1 LASTPIN (-4875 3700) $PN 2
J 0
(-4913 3712);
DISPLAY 0.787234 (-4913 3712);
PAINT ORANGE (-4913 3712);
FORCEPROP 1 LAST PART_NUMBER G22178-002
J 0
(-5000 3600);
DISPLAY 0.617021 (-5000 3600);
PAINT BLUE (-5000 3600);
FORCEPROP 1 LASTPIN (-5075 3700) $PN 1
J 0
(-5063 3712);
DISPLAY 0.787234 (-5063 3712);
PAINT ORANGE (-5063 3712);
FORCEPROP 1 LAST TOLERANCE 5.0%
J 0
(-4725 3650);
DISPLAY 0.617021 (-4725 3650);
PAINT SKYBLUE (-4725 3650);
FORCEPROP 1 LAST PACK_TYPE 0603
J 0
(-4900 3650);
DISPLAY 0.617021 (-4900 3650);
PAINT SKYBLUE (-4900 3650);
FORCEPROP 2 LAST CDS_LIB mstr_discrete
J 0
(-4975 3700);
PAINT MONO (-4975 3700);
DISPLAY INVISIBLE (-4975 3700);
FORCEPROP 1 LAST PATH I108
J 0
(-5025 3850);
DISPLAY 0.978723 (-5025 3850);
PAINT WHITE (-5025 3850);
DISPLAY INVISIBLE (-5025 3850);
FORCEPROP 0 LAST ROOM NIC_SPRV
J 0
(-4875 3825);
DISPLAY 1.021277 (-4875 3825);
PAINT ORANGE (-4875 3825);
DISPLAY INVISIBLE (-4875 3825);
FORCEPROP 0 LAST BOM_COST NT_GBE_BASE
J 0
(-4875 3925);
DISPLAY 1.021277 (-4875 3925);
PAINT ORANGE (-4875 3925);
DISPLAY INVISIBLE (-4875 3925);
FORCEPROP 0 LAST SEC 1
J 0
(-5225 3800);
DISPLAY 0.680851 (-5225 3800);
PAINT MONO (-5225 3800);
DISPLAY INVISIBLE (-5225 3800);
FORCEPROP 2 LAST SEC_TYPE 0603
J 0
(-5025 3900);
DISPLAY 1.021277 (-5025 3900);
PAINT ORANGE (-5025 3900);
DISPLAY INVISIBLE (-5025 3900);
FORCEADD RES..1
(-4975 1075);
FORCEPROP 1 LASTPIN (-5075 1075) $PN 1
J 0
(-5063 1087);
DISPLAY 0.787234 (-5063 1087);
PAINT ORANGE (-5063 1087);
FORCEPROP 1 LASTPIN (-4875 1075) $PN 2
J 0
(-4913 1087);
DISPLAY 0.787234 (-4913 1087);
PAINT ORANGE (-4913 1087);
FORCEPROP 1 LAST MATERIAL CHIP
J 0
(-4650 975);
DISPLAY 0.617021 (-4650 975);
PAINT SKYBLUE (-4650 975);
FORCEPROP 1 LAST TOLERANCE 5.0%
J 0
(-4650 1025);
DISPLAY 0.617021 (-4650 1025);
PAINT SKYBLUE (-4650 1025);
FORCEPROP 1 LAST PACK_TYPE 0603
J 0
(-4900 1025);
DISPLAY 0.617021 (-4900 1025);
PAINT SKYBLUE (-4900 1025);
FORCEPROP 1 LAST LOCATION RT14
J 0
(-5025 975);
DISPLAY 0.617021 (-5025 975);
PAINT AQUA (-5025 975);
FORCEPROP 1 LAST VALUE 0
J 2
(-5025 1025);
DISPLAY 0.617021 (-5025 1025);
PAINT SKYBLUE (-5025 1025);
FORCEPROP 1 LAST WATTAGE 1/10W
J 2
(-4550 925);
DISPLAY 0.617021 (-4550 925);
PAINT SKYBLUE (-4550 925);
FORCEPROP 1 LAST PART_NUMBER G22178-002
J 0
(-5075 925);
DISPLAY 0.617021 (-5075 925);
PAINT BLUE (-5075 925);
FORCEPROP 2 LAST CDS_LIB mstr_discrete
J 0
(-4975 1075);
PAINT MONO (-4975 1075);
DISPLAY INVISIBLE (-4975 1075);
FORCEPROP 1 LAST PATH I109
J 0
(-5025 1225);
DISPLAY 0.978723 (-5025 1225);
PAINT WHITE (-5025 1225);
DISPLAY INVISIBLE (-5025 1225);
FORCEPROP 0 LAST ROOM NIC_SPRV
J 0
(-4875 1200);
DISPLAY 1.021277 (-4875 1200);
PAINT ORANGE (-4875 1200);
DISPLAY INVISIBLE (-4875 1200);
FORCEPROP 0 LAST BOM_COST NT_GBE_BASE
J 0
(-4875 1300);
DISPLAY 1.021277 (-4875 1300);
PAINT ORANGE (-4875 1300);
DISPLAY INVISIBLE (-4875 1300);
FORCEPROP 0 LAST SEC 1
J 0
(-5225 1175);
DISPLAY 0.680851 (-5225 1175);
PAINT MONO (-5225 1175);
DISPLAY INVISIBLE (-5225 1175);
FORCEPROP 2 LAST SEC_TYPE 0603
J 0
(-5025 1275);
DISPLAY 1.021277 (-5025 1275);
PAINT ORANGE (-5025 1275);
DISPLAY INVISIBLE (-5025 1275);
FORCEADD RES..1
(-5350 4700);
FORCEPROP 1 LAST PART_NUMBER G21497-005
J 0
(-5450 4475);
DISPLAY 0.617021 (-5450 4475);
PAINT BLUE (-5450 4475);
FORCEPROP 1 LAST MATERIAL CHIP
J 0
(-5300 4525);
DISPLAY 0.510638 (-5300 4525);
PAINT SKYBLUE (-5300 4525);
FORCEPROP 1 LAST TOLERANCE 5%
J 0
(-5450 4525);
DISPLAY 0.617021 (-5450 4525);
PAINT SKYBLUE (-5450 4525);
FORCEPROP 1 LAST PACK_TYPE 0402
J 0
(-5300 4575);
DISPLAY 0.617021 (-5300 4575);
PAINT SKYBLUE (-5300 4575);
FORCEPROP 1 LAST WATTAGE 1/16W
J 0
(-5300 4625);
DISPLAY 0.510638 (-5300 4625);
PAINT SKYBLUE (-5300 4625);
FORCEPROP 1 LASTPIN (-5250 4700) $PN 2
J 0
(-5288 4712);
DISPLAY 0.617021 (-5288 4712);
PAINT WHITE (-5288 4712);
FORCEPROP 1 LAST LOCATION R9P22
J 0
(-5450 4625);
DISPLAY 0.617021 (-5450 4625);
PAINT AQUA (-5450 4625);
FORCEPROP 1 LAST VALUE 0.0
J 0
(-5450 4575);
DISPLAY 0.617021 (-5450 4575);
PAINT SKYBLUE (-5450 4575);
FORCEPROP 1 LASTPIN (-5450 4700) $PN 1
J 0
(-5438 4712);
DISPLAY 0.617021 (-5438 4712);
PAINT WHITE (-5438 4712);
FORCEPROP 2 LAST CDS_LOCATION R9P22
J 0
(-5825 4700);
DISPLAY 0.617021 (-5825 4700);
PAINT AQUA (-5825 4700);
DISPLAY INVISIBLE (-5825 4700);
FORCEPROP 1 LAST PATH I114
J 0
(-5400 4850);
DISPLAY 0.978723 (-5400 4850);
PAINT WHITE (-5400 4850);
DISPLAY INVISIBLE (-5400 4850);
FORCEPROP 2 LAST BOM_COST PROC_SIDEBAND
J 0
(-5350 4700);
PAINT MONO (-5350 4700);
DISPLAY INVISIBLE (-5350 4700);
FORCEPROP 2 LAST CDS_LIB mstr_discrete
J 0
(-5350 4700);
DISPLAY 1.340426 (-5350 4700);
PAINT ORANGE (-5350 4700);
DISPLAY INVISIBLE (-5350 4700);
FORCEPROP 2 LAST SEC_TYPE 0402
J 0
(-5400 4925);
DISPLAY 1.021277 (-5400 4925);
PAINT ORANGE (-5400 4925);
DISPLAY INVISIBLE (-5400 4925);
FORCEPROP 2 LAST SEC 1
J 0
(-5400 4925);
DISPLAY 0.680851 (-5400 4925);
PAINT MONO (-5400 4925);
DISPLAY INVISIBLE (-5400 4925);
FORCEPROP 2 LAST ROOM CPU0
J 0
(-5400 4850);
PAINT PEACH (-5400 4850);
DISPLAY INVISIBLE (-5400 4850);
FORCEPROP 0 LAST CDS_SEC 1
J 0
(-5050 4750);
PAINT MONO (-5050 4750);
DISPLAY INVISIBLE (-5050 4750);
FORCEADD RES..1
(-5450 2025);
FORCEPROP 1 LASTPIN (-5550 2025) $PN 1
J 0
(-5538 2037);
DISPLAY 0.617021 (-5538 2037);
PAINT WHITE (-5538 2037);
FORCEPROP 1 LAST PACK_TYPE 0402
J 0
(-5375 1925);
DISPLAY 0.617021 (-5375 1925);
PAINT SKYBLUE (-5375 1925);
FORCEPROP 1 LAST VALUE 0.0
J 2
(-5550 1925);
DISPLAY 0.617021 (-5550 1925);
PAINT SKYBLUE (-5550 1925);
FORCEPROP 1 LAST WATTAGE 1/16W
J 2
(-5100 2050);
DISPLAY 0.510638 (-5100 2050);
PAINT SKYBLUE (-5100 2050);
FORCEPROP 1 LAST TOLERANCE 5%
J 0
(-5500 1925);
DISPLAY 0.617021 (-5500 1925);
PAINT SKYBLUE (-5500 1925);
FORCEPROP 1 LAST LOCATION R9P8
J 0
(-5550 2075);
DISPLAY 0.617021 (-5550 2075);
PAINT AQUA (-5550 2075);
FORCEPROP 1 LASTPIN (-5350 2025) $PN 2
J 0
(-5388 2037);
DISPLAY 0.617021 (-5388 2037);
PAINT WHITE (-5388 2037);
FORCEPROP 1 LAST PART_NUMBER G21497-005
J 0
(-5575 1975);
DISPLAY 0.617021 (-5575 1975);
PAINT BLUE (-5575 1975);
FORCEPROP 1 LAST MATERIAL CHIP
J 0
(-5200 1925);
DISPLAY 0.510638 (-5200 1925);
PAINT SKYBLUE (-5200 1925);
FORCEPROP 1 LAST PATH I115
J 0
(-5500 2175);
DISPLAY 0.978723 (-5500 2175);
PAINT WHITE (-5500 2175);
DISPLAY INVISIBLE (-5500 2175);
FORCEPROP 2 LAST BOM_COST PROC_SIDEBAND
J 0
(-5450 2025);
PAINT MONO (-5450 2025);
DISPLAY INVISIBLE (-5450 2025);
FORCEPROP 2 LAST CDS_LIB mstr_discrete
J 0
(-5450 2025);
DISPLAY 1.340426 (-5450 2025);
PAINT ORANGE (-5450 2025);
DISPLAY INVISIBLE (-5450 2025);
FORCEPROP 2 LAST SEC_TYPE 0402
J 0
(-5500 2250);
DISPLAY 1.021277 (-5500 2250);
PAINT ORANGE (-5500 2250);
DISPLAY INVISIBLE (-5500 2250);
FORCEPROP 2 LAST SEC 1
J 0
(-5500 2250);
DISPLAY 0.680851 (-5500 2250);
PAINT MONO (-5500 2250);
DISPLAY INVISIBLE (-5500 2250);
FORCEPROP 2 LAST ROOM CPU0
J 0
(-5500 2175);
PAINT PEACH (-5500 2175);
DISPLAY INVISIBLE (-5500 2175);
FORCEPROP 0 LAST CDS_SEC 1
J 0
(-5150 2075);
PAINT MONO (-5150 2075);
DISPLAY INVISIBLE (-5150 2075);
FORCEPROP 2 LAST CDS_LOCATION R9P8
J 0
(-5925 2025);
DISPLAY 0.617021 (-5925 2025);
PAINT AQUA (-5925 2025);
DISPLAY INVISIBLE (-5925 2025);
FORCEADD IND-120NH-30-GP..1
R 1
(-1425 3650);
FORCEPROP 1 LAST VALUE IND-120NH-30-GP
J 0
(-1575 3550);
DISPLAY 0.617021 (-1575 3550);
PAINT GREEN (-1575 3550);
FORCEPROP 1 LAST LOCATION L1D2
J 0
(-1575 3700);
DISPLAY 0.617021 (-1575 3700);
PAINT GREEN (-1575 3700);
FORCEPROP 2 LASTPIN (-1575 3625) $PN 1
J 2
(-1585 3635);
DISPLAY 0.808511 (-1585 3635);
PAINT ORANGE (-1585 3635);
FORCEPROP 2 LASTPIN (-1275 3625) $PN 2
J 0
(-1265 3635);
DISPLAY 0.808511 (-1265 3635);
PAINT ORANGE (-1265 3635);
FORCEPROP 2 LAST ATTRIBUTE 120NH
J 0
(-1575 3500);
DISPLAY 0.638298 (-1575 3500);
PAINT GREEN (-1575 3500);
FORCEPROP 2 LAST RATED ISAT=94A@25C
J 0
(-1575 3450);
DISPLAY 0.638298 (-1575 3450);
PAINT GREEN (-1575 3450);
FORCEPROP 2 LAST PACK_SIZE DCR=0.17MOHM
J 0
(-1575 3350);
DISPLAY 0.638298 (-1575 3350);
PAINT GREEN (-1575 3350);
FORCEPROP 2 LAST TYPE IRMS=66A@DELTA_T<40C
J 0
(-1575 3400);
DISPLAY 0.638298 (-1575 3400);
PAINT GREEN (-1575 3400);
FORCEPROP 1 LAST PACK_TYPE DISCRET-GB2
R 1
J 0
(-1425 3650);
DISPLAY 0.617021 (-1425 3650);
PAINT GREEN (-1425 3650);
DISPLAY INVISIBLE (-1425 3650);
FORCEPROP 2 LAST SEC 1
J 0
(-1550 3725);
DISPLAY 0.680851 (-1550 3725);
PAINT MONO (-1550 3725);
DISPLAY INVISIBLE (-1550 3725);
FORCEPROP 2 LAST SEC_TYPE DISCRET-GB2
J 0
(-1550 3725);
DISPLAY 1.021277 (-1550 3725);
PAINT ORANGE (-1550 3725);
DISPLAY INVISIBLE (-1550 3725);
FORCEPROP 1 LAST CDS_LMAN_SYM_OUTLINE -75,100,75,-100
R 1
J 0
(-1425 3650);
DISPLAY 0.468085 (-1425 3650);
PAINT GREEN (-1425 3650);
DISPLAY INVISIBLE (-1425 3650);
FORCEPROP 2 LAST CDS_LIB w_hdl
R 1
J 0
(-1425 3650);
PAINT MONO (-1425 3650);
DISPLAY INVISIBLE (-1425 3650);
FORCEPROP 1 LAST PART_NUMBER 068.1202N.M001
R 1
J 0
(-1425 3650);
DISPLAY 0.617021 (-1425 3650);
PAINT GREEN (-1425 3650);
DISPLAY INVISIBLE (-1425 3650);
FORCEPROP 1 LAST PATH I116
R 1
J 0
(-1425 3650);
DISPLAY 0.617021 (-1425 3650);
PAINT GREEN (-1425 3650);
DISPLAY INVISIBLE (-1425 3650);
FORCEADD IND-120NH-30-GP..1
R 1
(-1275 1050);
FORCEPROP 2 LASTPIN (-1425 1025) $PN 1
J 2
(-1435 1035);
DISPLAY 0.808511 (-1435 1035);
PAINT ORANGE (-1435 1035);
FORCEPROP 2 LASTPIN (-1125 1025) $PN 2
J 0
(-1115 1035);
DISPLAY 0.808511 (-1115 1035);
PAINT ORANGE (-1115 1035);
FORCEPROP 1 LAST LOCATION L1D1
J 0
(-1425 1100);
DISPLAY 0.617021 (-1425 1100);
PAINT GREEN (-1425 1100);
FORCEPROP 1 LAST VALUE IND-120NH-30-GP
J 0
(-1425 950);
DISPLAY 0.617021 (-1425 950);
PAINT GREEN (-1425 950);
FORCEPROP 2 LAST ATTRIBUTE 120NH
J 0
(-1425 900);
DISPLAY 0.638298 (-1425 900);
PAINT GREEN (-1425 900);
FORCEPROP 2 LAST RATED ISAT=94A@25C
J 0
(-1425 850);
DISPLAY 0.638298 (-1425 850);
PAINT GREEN (-1425 850);
FORCEPROP 2 LAST PACK_SIZE DCR=0.17MOHM
J 0
(-1425 750);
DISPLAY 0.638298 (-1425 750);
PAINT GREEN (-1425 750);
FORCEPROP 2 LAST TYPE IRMS=66A@DELTA_T<40C
J 0
(-1425 800);
DISPLAY 0.638298 (-1425 800);
PAINT GREEN (-1425 800);
FORCEPROP 1 LAST PACK_TYPE DISCRET-GB2
R 1
J 0
(-1275 1050);
DISPLAY 0.617021 (-1275 1050);
PAINT GREEN (-1275 1050);
DISPLAY INVISIBLE (-1275 1050);
FORCEPROP 2 LAST SEC 1
J 0
(-1400 1125);
DISPLAY 0.680851 (-1400 1125);
PAINT MONO (-1400 1125);
DISPLAY INVISIBLE (-1400 1125);
FORCEPROP 2 LAST SEC_TYPE DISCRET-GB2
J 0
(-1400 1125);
DISPLAY 1.021277 (-1400 1125);
PAINT ORANGE (-1400 1125);
DISPLAY INVISIBLE (-1400 1125);
FORCEPROP 1 LAST CDS_LMAN_SYM_OUTLINE -75,100,75,-100
R 1
J 0
(-1275 1050);
DISPLAY 0.468085 (-1275 1050);
PAINT GREEN (-1275 1050);
DISPLAY INVISIBLE (-1275 1050);
FORCEPROP 2 LAST CDS_LIB w_hdl
R 1
J 0
(-1275 1050);
PAINT MONO (-1275 1050);
DISPLAY INVISIBLE (-1275 1050);
FORCEPROP 1 LAST PART_NUMBER 068.1202N.M001
R 1
J 0
(-1275 1050);
DISPLAY 0.617021 (-1275 1050);
PAINT GREEN (-1275 1050);
DISPLAY INVISIBLE (-1275 1050);
FORCEPROP 1 LAST PATH I117
R 1
J 0
(-1275 1050);
DISPLAY 0.617021 (-1275 1050);
PAINT GREEN (-1275 1050);
DISPLAY INVISIBLE (-1275 1050);
FORCEADD SC1U10V2KX-4-GP..1
(-5100 4200);
FORCEPROP 2 LAST TOLERANCE 10%
J 0
(-4975 4175);
DISPLAY 0.638298 (-4975 4175);
PAINT GREEN (-4975 4175);
FORCEPROP 2 LAST RATED 10V
J 0
(-4975 4125);
DISPLAY 0.638298 (-4975 4125);
PAINT GREEN (-4975 4125);
FORCEPROP 2 LAST PACK_SIZE 0402
J 0
(-4975 4075);
DISPLAY 0.638298 (-4975 4075);
PAINT GREEN (-4975 4075);
FORCEPROP 1 LAST VALUE SC1U10V2KX-4-GP
R 1
J 0
(-5000 3950);
DISPLAY 0.617021 (-5000 3950);
PAINT GREEN (-5000 3950);
FORCEPROP 2 LASTPIN (-5100 4275) $PN 1
R 1
J 0
(-5110 4285);
DISPLAY 0.808511 (-5110 4285);
PAINT ORANGE (-5110 4285);
FORCEPROP 2 LASTPIN (-5100 4125) $PN 2
R 1
J 2
(-5110 4115);
DISPLAY 0.808511 (-5110 4115);
PAINT ORANGE (-5110 4115);
FORCEPROP 2 LAST ATTRIBUTE 1UF
J 0
(-4975 4225);
DISPLAY 0.638298 (-4975 4225);
PAINT GREEN (-4975 4225);
FORCEPROP 1 LAST LOCATION C1D15
J 0
(-4975 4280);
DISPLAY 0.617021 (-4975 4280);
PAINT GREEN (-4975 4280);
FORCEPROP 1 LAST PART_NUMBER 78.10523.8FL
J 0
(-5100 4200);
DISPLAY 0.617021 (-5100 4200);
PAINT GREEN (-5100 4200);
DISPLAY INVISIBLE (-5100 4200);
FORCEPROP 2 LAST CDS_LIB w_hdl
J 0
(-5100 4200);
PAINT MONO (-5100 4200);
DISPLAY INVISIBLE (-5100 4200);
FORCEPROP 1 LAST PATH I118
J 0
(-5100 4200);
DISPLAY 0.617021 (-5100 4200);
PAINT GREEN (-5100 4200);
DISPLAY INVISIBLE (-5100 4200);
FORCEPROP 1 LAST CDS_LMAN_SYM_OUTLINE -50,25,50,-25
J 0
(-5100 4200);
DISPLAY 0.468085 (-5100 4200);
PAINT GREEN (-5100 4200);
DISPLAY INVISIBLE (-5100 4200);
FORCEPROP 2 LAST SEC_TYPE SMD-BCG6
J 0
(-5075 4275);
DISPLAY 1.021277 (-5075 4275);
PAINT ORANGE (-5075 4275);
DISPLAY INVISIBLE (-5075 4275);
FORCEPROP 2 LAST SEC 1
J 0
(-5075 4275);
DISPLAY 0.680851 (-5075 4275);
PAINT MONO (-5075 4275);
DISPLAY INVISIBLE (-5075 4275);
FORCEPROP 1 LAST PACK_TYPE SMD-BCG6
J 0
(-5100 4200);
DISPLAY 0.617021 (-5100 4200);
PAINT GREEN (-5100 4200);
DISPLAY INVISIBLE (-5100 4200);
FORCEADD SC1U10V2KX-4-GP..1
(-5200 1550);
FORCEPROP 2 LASTPIN (-5200 1475) $PN 2
R 1
J 2
(-5210 1465);
DISPLAY 0.808511 (-5210 1465);
PAINT ORANGE (-5210 1465);
FORCEPROP 2 LASTPIN (-5200 1625) $PN 1
R 1
J 0
(-5210 1635);
DISPLAY 0.808511 (-5210 1635);
PAINT ORANGE (-5210 1635);
FORCEPROP 1 LAST LOCATION C1D5
J 0
(-5075 1630);
DISPLAY 0.617021 (-5075 1630);
PAINT GREEN (-5075 1630);
FORCEPROP 1 LAST VALUE SC1U10V2KX-4-GP
R 1
J 0
(-5100 1325);
DISPLAY 0.617021 (-5100 1325);
PAINT GREEN (-5100 1325);
FORCEPROP 2 LAST ATTRIBUTE 1UF
J 0
(-5075 1575);
DISPLAY 0.638298 (-5075 1575);
PAINT GREEN (-5075 1575);
FORCEPROP 2 LAST TOLERANCE 10%
J 0
(-5075 1525);
DISPLAY 0.638298 (-5075 1525);
PAINT GREEN (-5075 1525);
FORCEPROP 2 LAST RATED 10V
J 0
(-5075 1475);
DISPLAY 0.638298 (-5075 1475);
PAINT GREEN (-5075 1475);
FORCEPROP 2 LAST PACK_SIZE 0402
J 0
(-5075 1425);
DISPLAY 0.638298 (-5075 1425);
PAINT GREEN (-5075 1425);
FORCEPROP 1 LAST PART_NUMBER 78.10523.8FL
J 0
(-5200 1550);
DISPLAY 0.617021 (-5200 1550);
PAINT GREEN (-5200 1550);
DISPLAY INVISIBLE (-5200 1550);
FORCEPROP 2 LAST CDS_LIB w_hdl
J 0
(-5200 1550);
PAINT MONO (-5200 1550);
DISPLAY INVISIBLE (-5200 1550);
FORCEPROP 1 LAST PATH I119
J 0
(-5200 1550);
DISPLAY 0.617021 (-5200 1550);
PAINT GREEN (-5200 1550);
DISPLAY INVISIBLE (-5200 1550);
FORCEPROP 1 LAST CDS_LMAN_SYM_OUTLINE -50,25,50,-25
J 0
(-5200 1550);
DISPLAY 0.468085 (-5200 1550);
PAINT GREEN (-5200 1550);
DISPLAY INVISIBLE (-5200 1550);
FORCEPROP 2 LAST SEC_TYPE SMD-BCG6
J 0
(-5175 1625);
DISPLAY 1.021277 (-5175 1625);
PAINT ORANGE (-5175 1625);
DISPLAY INVISIBLE (-5175 1625);
FORCEPROP 2 LAST SEC 1
J 0
(-5175 1625);
DISPLAY 0.680851 (-5175 1625);
PAINT MONO (-5175 1625);
DISPLAY INVISIBLE (-5175 1625);
FORCEPROP 1 LAST PACK_TYPE SMD-BCG6
J 0
(-5200 1550);
DISPLAY 0.617021 (-5200 1550);
PAINT GREEN (-5200 1550);
DISPLAY INVISIBLE (-5200 1550);
FORCEADD CAPP..1
(-1450 2650);
FORCEPROP 1 LAST LOCATION C9P8
J 0
(-1400 2750);
DISPLAY 0.617021 (-1400 2750);
PAINT AQUA (-1400 2750);
FORCEPROP 1 LASTPIN (-1450 2550) $PN 2
J 0
(-1440 2535);
DISPLAY 0.617021 (-1440 2535);
PAINT GREEN (-1440 2535);
FORCEPROP 1 LAST TOLERANCE 20%
J 0
(-1400 2650);
DISPLAY 0.617021 (-1400 2650);
PAINT SKYBLUE (-1400 2650);
FORCEPROP 1 LAST VALUE 470UF
J 0
(-1400 2700);
DISPLAY 0.617021 (-1400 2700);
PAINT SKYBLUE (-1400 2700);
FORCEPROP 1 LASTPIN (-1450 2750) $PN 1
J 0
(-1440 2735);
DISPLAY 0.617021 (-1440 2735);
PAINT GREEN (-1440 2735);
FORCEPROP 1 LAST PACK_TYPE 3018
J 0
(-1400 2500);
DISPLAY 0.617021 (-1400 2500);
PAINT SKYBLUE (-1400 2500);
FORCEPROP 1 LAST PART_NUMBER 699013-049
J 0
(-1400 2450);
DISPLAY 0.617021 (-1400 2450);
PAINT BLUE (-1400 2450);
FORCEPROP 1 LAST VOLTAGE 2.5V
J 0
(-1400 2600);
DISPLAY 0.638298 (-1400 2600);
PAINT SKYBLUE (-1400 2600);
FORCEPROP 1 LAST MATERIAL ALUM
J 0
(-1400 2550);
DISPLAY 0.617021 (-1400 2550);
PAINT SKYBLUE (-1400 2550);
FORCEPROP 0 LAST GROUP PWR_BULK_CAP
J 0
(-1404 2401);
DISPLAY 0.638298 (-1404 2401);
PAINT BROWN (-1404 2401);
DISPLAY BOTH (-1404 2401);
FORCEPROP 2 LAST CDS_LIB mstr_discrete
J 0
(-1450 2650);
PAINT MONO (-1450 2650);
DISPLAY INVISIBLE (-1450 2650);
FORCEPROP 2 LAST ROOM PVCCIN_CPU1_DECAP_VR
J 0
(-1400 2775);
PAINT MONO (-1400 2775);
DISPLAY INVISIBLE (-1400 2775);
FORCEPROP 1 LAST PATH I12
J 0
(-1400 2800);
DISPLAY 0.978723 (-1400 2800);
PAINT ORANGE (-1400 2800);
DISPLAY INVISIBLE (-1400 2800);
FORCEPROP 2 LAST CDS_LOCATION C9P8
J 0
(-1400 2750);
DISPLAY 0.617021 (-1400 2750);
PAINT AQUA (-1400 2750);
DISPLAY INVISIBLE (-1400 2750);
FORCEPROP 2 LAST BOM_COST PROC_VRD_VCCIN_CPU0
J 0
(-1400 2800);
PAINT MONO (-1400 2800);
DISPLAY INVISIBLE (-1400 2800);
FORCEPROP 2 LAST SEC 1
J 0
(-1400 2850);
PAINT MONO (-1400 2850);
DISPLAY INVISIBLE (-1400 2850);
FORCEPROP 2 LAST SEC_TYPE 3018
J 0
(-1385 2860);
DISPLAY 1.021277 (-1385 2860);
PAINT ORANGE (-1385 2860);
DISPLAY INVISIBLE (-1385 2860);
FORCEADD 1R3F-GP..1
(-2225 3175);
FORCEPROP 2 LAST PACK_SIZE 0603
J 0
(-2175 3050);
DISPLAY 0.638298 (-2175 3050);
PAINT GREEN (-2175 3050);
FORCEPROP 2 LAST RATED 1/10W
J 0
(-2175 3100);
DISPLAY 0.638298 (-2175 3100);
PAINT GREEN (-2175 3100);
FORCEPROP 1 LAST LOCATION RT12
J 0
(-2175 3300);
DISPLAY 0.617021 (-2175 3300);
PAINT GREEN (-2175 3300);
FORCEPROP 2 LAST ATTRIBUTE 1 OHM
J 0
(-2175 3200);
DISPLAY 0.638298 (-2175 3200);
PAINT GREEN (-2175 3200);
FORCEPROP 1 LAST VALUE 1R3F-GP
J 0
(-2175 3250);
DISPLAY 0.617021 (-2175 3250);
PAINT GREEN (-2175 3250);
FORCEPROP 0 LAST POP NOPOP
J 0
(-2175 3000);
DISPLAY 0.638298 (-2175 3000);
PAINT RED (-2175 3000);
FORCEPROP 2 LASTPIN (-2225 3300) $PN 1
R 1
J 0
(-2235 3310);
DISPLAY 0.808511 (-2235 3310);
PAINT ORANGE (-2235 3310);
FORCEPROP 2 LASTPIN (-2225 3050) $PN 2
R 1
J 2
(-2235 3040);
DISPLAY 0.808511 (-2235 3040);
PAINT ORANGE (-2235 3040);
FORCEPROP 2 LAST TOLERANCE 1%
J 0
(-2175 3150);
DISPLAY 0.638298 (-2175 3150);
PAINT GREEN (-2175 3150);
FORCEPROP 1 LAST CDS_LMAN_SYM_OUTLINE -50,75,50,-75
J 0
(-2225 3175);
DISPLAY 0.468085 (-2225 3175);
PAINT GREEN (-2225 3175);
DISPLAY INVISIBLE (-2225 3175);
FORCEPROP 2 LAST CDS_LIB w_hdl
J 0
(-2225 3175);
DISPLAY INVISIBLE (-2225 3175);
FORCEPROP 1 LAST PART_NUMBER 64.1R005.55L
J 0
(-2225 3175);
DISPLAY 0.617021 (-2225 3175);
PAINT GREEN (-2225 3175);
DISPLAY INVISIBLE (-2225 3175);
FORCEPROP 2 LAST SEC_TYPE RCL_GP
J 0
(-2175 3275);
DISPLAY 1.021277 (-2175 3275);
PAINT ORANGE (-2175 3275);
DISPLAY INVISIBLE (-2175 3275);
FORCEPROP 2 LAST SEC 1
J 0
(-2175 3275);
DISPLAY 0.680851 (-2175 3275);
PAINT MONO (-2175 3275);
DISPLAY INVISIBLE (-2175 3275);
FORCEPROP 1 LAST PACK_TYPE RCL_GP
J 0
(-2225 3175);
DISPLAY 0.617021 (-2225 3175);
PAINT GREEN (-2225 3175);
DISPLAY INVISIBLE (-2225 3175);
FORCEPROP 1 LAST PATH I120
J 0
(-2225 3175);
DISPLAY 0.617021 (-2225 3175);
PAINT GREEN (-2225 3175);
DISPLAY INVISIBLE (-2225 3175);
FORCEADD 1R3F-GP..1
(-2075 550);
FORCEPROP 2 LAST PACK_SIZE 0603
J 0
(-2025 425);
DISPLAY 0.638298 (-2025 425);
PAINT GREEN (-2025 425);
FORCEPROP 2 LAST RATED 1/10W
J 0
(-2025 475);
DISPLAY 0.638298 (-2025 475);
PAINT GREEN (-2025 475);
FORCEPROP 1 LAST LOCATION RT13
J 0
(-2025 675);
DISPLAY 0.617021 (-2025 675);
PAINT GREEN (-2025 675);
FORCEPROP 1 LAST VALUE 1R3F-GP
J 0
(-2025 625);
DISPLAY 0.617021 (-2025 625);
PAINT GREEN (-2025 625);
FORCEPROP 2 LAST ATTRIBUTE 1 OHM
J 0
(-2025 575);
DISPLAY 0.638298 (-2025 575);
PAINT GREEN (-2025 575);
FORCEPROP 0 LAST POP NOPOP
J 0
(-2025 375);
DISPLAY 0.638298 (-2025 375);
PAINT RED (-2025 375);
FORCEPROP 2 LAST TOLERANCE 1%
J 0
(-2025 525);
DISPLAY 0.638298 (-2025 525);
PAINT GREEN (-2025 525);
FORCEPROP 2 LASTPIN (-2075 425) $PN 2
R 1
J 2
(-2085 415);
DISPLAY 0.808511 (-2085 415);
PAINT ORANGE (-2085 415);
FORCEPROP 2 LASTPIN (-2075 675) $PN 1
R 1
J 0
(-2085 685);
DISPLAY 0.808511 (-2085 685);
PAINT ORANGE (-2085 685);
FORCEPROP 1 LAST PACK_TYPE RCL_GP
J 0
(-2075 550);
DISPLAY 0.617021 (-2075 550);
PAINT GREEN (-2075 550);
DISPLAY INVISIBLE (-2075 550);
FORCEPROP 2 LAST SEC 1
J 0
(-2025 650);
DISPLAY 0.680851 (-2025 650);
PAINT MONO (-2025 650);
DISPLAY INVISIBLE (-2025 650);
FORCEPROP 2 LAST SEC_TYPE RCL_GP
J 0
(-2025 650);
DISPLAY 1.021277 (-2025 650);
PAINT ORANGE (-2025 650);
DISPLAY INVISIBLE (-2025 650);
FORCEPROP 1 LAST PART_NUMBER 64.1R005.55L
J 0
(-2075 550);
DISPLAY 0.617021 (-2075 550);
PAINT GREEN (-2075 550);
DISPLAY INVISIBLE (-2075 550);
FORCEPROP 2 LAST CDS_LIB w_hdl
J 0
(-2075 550);
DISPLAY INVISIBLE (-2075 550);
FORCEPROP 1 LAST CDS_LMAN_SYM_OUTLINE -50,75,50,-75
J 0
(-2075 550);
DISPLAY 0.468085 (-2075 550);
PAINT GREEN (-2075 550);
DISPLAY INVISIBLE (-2075 550);
FORCEPROP 1 LAST PATH I121
J 0
(-2075 550);
DISPLAY 0.617021 (-2075 550);
PAINT GREEN (-2075 550);
DISPLAY INVISIBLE (-2075 550);
FORCEADD GND..1
(-1000 2275);
FORCEPROP 3 LASTPIN (-1000 2325) SIG_NAME GND\g
J 0
(-990 2335);
DISPLAY 0.659574 (-990 2335);
PAINT MONO (-990 2335);
DISPLAY INVISIBLE (-990 2335);
FORCEPROP 1 LAST HDL_POWER GND
J 0
(-1000 2425);
DISPLAY 0.893617 (-1000 2425);
PAINT GREEN (-1000 2425);
DISPLAY INVISIBLE (-1000 2425);
FORCEPROP 1 LAST BODY_TYPE PLUMBING
J 0
(-1045 2232);
DISPLAY 0.340426 (-1045 2232);
PAINT GREEN (-1045 2232);
DISPLAY INVISIBLE (-1045 2232);
FORCEPROP 1 LAST VOLTAGE 0
J 0
(-1000 2275);
PAINT SKYBLUE (-1000 2275);
DISPLAY INVISIBLE (-1000 2275);
FORCEPROP 2 LAST CDS_LIB mstr_symbols
J 1
(-1000 2275);
PAINT ORANGE (-1000 2275);
DISPLAY INVISIBLE (-1000 2275);
FORCEPROP 1 LAST PATH I13
J 0
(-925 2275);
DISPLAY 0.872340 (-925 2275);
PAINT AQUA (-925 2275);
DISPLAY INVISIBLE (-925 2275);
FORCEPROP 1 LAST SIZE 1B
J 0
(-925 2225);
DISPLAY 0.893617 (-925 2225);
PAINT GREEN (-925 2225);
DISPLAY INVISIBLE (-925 2225);
FORCEPROP 2 LAST BOM_COST PROC_VRD_VCCIN_CPU0
J 0
(-1375 2350);
PAINT MONO (-1375 2350);
DISPLAY INVISIBLE (-1375 2350);
FORCEPROP 2 LAST ROOM PVCCIN_CPU1_DECAP_VR
J 0
(-1550 2350);
PAINT ORANGE (-1550 2350);
DISPLAY INVISIBLE (-1550 2350);
FORCEADD CAPP..1
(-1925 2650);
FORCEPROP 1 LAST MATERIAL ALUM
J 0
(-1875 2550);
DISPLAY 0.617021 (-1875 2550);
PAINT SKYBLUE (-1875 2550);
FORCEPROP 1 LAST VALUE 470UF
J 0
(-1875 2700);
DISPLAY 0.617021 (-1875 2700);
PAINT SKYBLUE (-1875 2700);
FORCEPROP 1 LAST TOLERANCE 20%
J 0
(-1875 2650);
DISPLAY 0.617021 (-1875 2650);
PAINT SKYBLUE (-1875 2650);
FORCEPROP 1 LAST LOCATION C9P5
J 0
(-1875 2750);
DISPLAY 0.617021 (-1875 2750);
PAINT AQUA (-1875 2750);
FORCEPROP 1 LASTPIN (-1925 2750) $PN 1
J 0
(-1915 2735);
DISPLAY 0.617021 (-1915 2735);
PAINT GREEN (-1915 2735);
FORCEPROP 1 LAST PART_NUMBER 699013-049
J 0
(-1875 2450);
DISPLAY 0.617021 (-1875 2450);
PAINT BLUE (-1875 2450);
FORCEPROP 1 LAST PACK_TYPE 3018
J 0
(-1875 2500);
DISPLAY 0.617021 (-1875 2500);
PAINT SKYBLUE (-1875 2500);
FORCEPROP 1 LASTPIN (-1925 2550) $PN 2
J 0
(-1915 2535);
DISPLAY 0.617021 (-1915 2535);
PAINT GREEN (-1915 2535);
FORCEPROP 0 LAST GROUP PWR_BULK_CAP
J 0
(-1879 2401);
DISPLAY 0.638298 (-1879 2401);
PAINT BROWN (-1879 2401);
DISPLAY BOTH (-1879 2401);
FORCEPROP 1 LAST VOLTAGE 2.5V
J 0
(-1875 2600);
DISPLAY 0.638298 (-1875 2600);
PAINT SKYBLUE (-1875 2600);
FORCEPROP 2 LAST CDS_LIB mstr_discrete
J 0
(-1925 2650);
PAINT MONO (-1925 2650);
DISPLAY INVISIBLE (-1925 2650);
FORCEPROP 2 LAST ROOM PVCCIN_CPU1_DECAP_VR
J 0
(-1875 2775);
PAINT MONO (-1875 2775);
DISPLAY INVISIBLE (-1875 2775);
FORCEPROP 1 LAST PATH I14
J 0
(-1875 2800);
DISPLAY 0.978723 (-1875 2800);
PAINT ORANGE (-1875 2800);
DISPLAY INVISIBLE (-1875 2800);
FORCEPROP 2 LAST CDS_LOCATION C9P5
J 0
(-1875 2750);
DISPLAY 0.617021 (-1875 2750);
PAINT AQUA (-1875 2750);
DISPLAY INVISIBLE (-1875 2750);
FORCEPROP 2 LAST BOM_COST PROC_VRD_VCCIN_CPU0
J 0
(-1875 2800);
PAINT MONO (-1875 2800);
DISPLAY INVISIBLE (-1875 2800);
FORCEPROP 2 LAST SEC 1
J 0
(-1875 2850);
PAINT MONO (-1875 2850);
DISPLAY INVISIBLE (-1875 2850);
FORCEPROP 2 LAST SEC_TYPE 3018
J 0
(-1860 2860);
DISPLAY 1.021277 (-1860 2860);
PAINT ORANGE (-1860 2860);
DISPLAY INVISIBLE (-1860 2860);
FORCEADD OFFPAGE..2
(-825 1825);
FORCEPROP 2 LAST $XR0 206 
J 0
(-636 1825);
DISPLAY 0.638298 (-636 1825);
PAINT MONO (-636 1825);
FORCEPROP 1 LAST COMMENT_BODY TRUE
J 0
(-870 1730);
DISPLAY 1.723404 (-870 1730);
PAINT GREEN (-870 1730);
DISPLAY INVISIBLE (-870 1730);
FORCEPROP 1 LAST OFFPAGE TRUE
J 0
(-500 1700);
DISPLAY 1.723404 (-500 1700);
PAINT GREEN (-500 1700);
DISPLAY INVISIBLE (-500 1700);
FORCEPROP 2 LAST BOM_COST PROC_VRD_VCCIN_CPU0
J 0
(-625 1875);
DISPLAY 1.446809 (-625 1875);
PAINT MONO (-625 1875);
DISPLAY INVISIBLE (-625 1875);
FORCEPROP 2 LAST PATH I16
J 0
(-620 1875);
DISPLAY 1.021277 (-620 1875);
PAINT ORANGE (-620 1875);
DISPLAY INVISIBLE (-620 1875);
FORCEPROP 2 LAST CDS_LIB mstr_standard
J 0
(-825 1825);
PAINT ORANGE (-825 1825);
DISPLAY INVISIBLE (-825 1825);
FORCEPROP 2 LAST ROOM PVCCIN_CPU1_PWR_VR
J 0
(-1225 1900);
DISPLAY 1.936170 (-1225 1900);
PAINT ORANGE (-1225 1900);
DISPLAY INVISIBLE (-1225 1900);
FORCEADD OFFPAGE..2
(-1675 1450);
FORCEPROP 2 LAST $XR3 206 
J 0
(-1126 1450);
DISPLAY 0.638298 (-1126 1450);
PAINT MONO (-1126 1450);
FORCEPROP 2 LAST $XR2 209 
J 0
(-1246 1450);
DISPLAY 0.638298 (-1246 1450);
PAINT MONO (-1246 1450);
FORCEPROP 2 LAST $XR1 208 
J 0
(-1366 1450);
DISPLAY 0.638298 (-1366 1450);
PAINT MONO (-1366 1450);
FORCEPROP 2 LAST $XR0 207 
J 0
(-1486 1450);
DISPLAY 0.638298 (-1486 1450);
PAINT MONO (-1486 1450);
FORCEPROP 1 LAST COMMENT_BODY TRUE
J 0
(-1720 1355);
DISPLAY 1.723404 (-1720 1355);
PAINT GREEN (-1720 1355);
DISPLAY INVISIBLE (-1720 1355);
FORCEPROP 1 LAST OFFPAGE TRUE
J 0
(-1350 1325);
DISPLAY 1.723404 (-1350 1325);
PAINT GREEN (-1350 1325);
DISPLAY INVISIBLE (-1350 1325);
FORCEPROP 2 LAST ROOM PVCCIN_CPU1_PWR_VR
J 0
(-2075 1525);
DISPLAY 1.936170 (-2075 1525);
PAINT ORANGE (-2075 1525);
DISPLAY INVISIBLE (-2075 1525);
FORCEPROP 2 LAST CDS_LIB mstr_standard
J 0
(-1675 1450);
PAINT ORANGE (-1675 1450);
DISPLAY INVISIBLE (-1675 1450);
FORCEPROP 2 LAST PATH I17
J 0
(-1245 1500);
DISPLAY 1.021277 (-1245 1500);
PAINT ORANGE (-1245 1500);
DISPLAY INVISIBLE (-1245 1500);
FORCEPROP 2 LAST BOM_COST PROC_VRD_VCCIN_CPU0
J 0
(-1475 1500);
DISPLAY 1.446809 (-1475 1500);
PAINT MONO (-1475 1500);
DISPLAY INVISIBLE (-1475 1500);
FORCEADD PVCCIN_CPU1..1
(-350 1125);
FORCEPROP 3 LASTPIN (-350 1075) SIG_NAME PVCCIN_CPU1\g
J 0
(-340 1085);
DISPLAY 0.659574 (-340 1085);
PAINT MONO (-340 1085);
DISPLAY INVISIBLE (-340 1085);
FORCEPROP 1 LAST HDL_POWER PVCCIN_CPU1
J 1
(-350 1175);
DISPLAY 0.872340 (-350 1175);
PAINT GREEN (-350 1175);
DISPLAY INVISIBLE (-350 1175);
FORCEPROP 1 LAST BODY_TYPE PLUMBING
J 0
(-395 1082);
DISPLAY 0.340426 (-395 1082);
PAINT GREEN (-395 1082);
DISPLAY INVISIBLE (-395 1082);
FORCEPROP 1 LAST VOLTAGE 2.0V
J 0
(-395 1082);
DISPLAY 0.340426 (-395 1082);
PAINT SKYBLUE (-395 1082);
DISPLAY INVISIBLE (-395 1082);
FORCEPROP 2 LAST CDS_LIB mstr_symbols
J 0
(-350 1125);
PAINT ORANGE (-350 1125);
DISPLAY INVISIBLE (-350 1125);
FORCEPROP 1 LAST PATH I18
J 0
(-300 1150);
DISPLAY 0.872340 (-300 1150);
PAINT AQUA (-300 1150);
DISPLAY INVISIBLE (-300 1150);
FORCEADD GND..1
(-350 450);
FORCEPROP 3 LASTPIN (-350 500) SIG_NAME GND\g
J 0
(-340 510);
DISPLAY 0.659574 (-340 510);
PAINT MONO (-340 510);
DISPLAY INVISIBLE (-340 510);
FORCEPROP 1 LAST HDL_POWER GND
J 0
(-350 600);
DISPLAY 1.723404 (-350 600);
PAINT GREEN (-350 600);
DISPLAY INVISIBLE (-350 600);
FORCEPROP 1 LAST BODY_TYPE PLUMBING
J 0
(-395 407);
DISPLAY 0.340426 (-395 407);
PAINT GREEN (-395 407);
DISPLAY INVISIBLE (-395 407);
FORCEPROP 1 LAST VOLTAGE 0
J 0
(-350 450);
PAINT SKYBLUE (-350 450);
DISPLAY INVISIBLE (-350 450);
FORCEPROP 1 LAST SIZE 1B
J 0
(-275 400);
DISPLAY 1.723404 (-275 400);
PAINT GREEN (-275 400);
DISPLAY INVISIBLE (-275 400);
FORCEPROP 2 LAST CDS_LIB mstr_symbols
J 0
(-350 450);
PAINT ORANGE (-350 450);
DISPLAY INVISIBLE (-350 450);
FORCEPROP 1 LAST PATH I21
J 0
(-275 450);
DISPLAY 0.872340 (-275 450);
PAINT AQUA (-275 450);
DISPLAY INVISIBLE (-275 450);
FORCEPROP 2 LAST BOM_COST PROC_VRD_VCCIN_CPU0
J 0
(-725 525);
DISPLAY 1.446809 (-725 525);
PAINT MONO (-725 525);
DISPLAY INVISIBLE (-725 525);
FORCEPROP 2 LAST ROOM PVCCIN_CPU1_PWR_VR
J 0
(-900 525);
DISPLAY 1.936170 (-900 525);
PAINT ORANGE (-900 525);
DISPLAY INVISIBLE (-900 525);
FORCEADD CAP_A..1
(-700 800);
FORCEPROP 1 LAST LOCATION C1D3
J 0
(-650 900);
DISPLAY 0.617021 (-650 900);
PAINT AQUA (-650 900);
FORCEPROP 1 LAST VALUE 22.0UF
J 0
(-650 850);
DISPLAY 0.617021 (-650 850);
PAINT SKYBLUE (-650 850);
FORCEPROP 1 LASTPIN (-700 700) $PN 2
J 0
(-690 680);
DISPLAY 0.617021 (-690 680);
PAINT ORANGE (-690 680);
FORCEPROP 1 LASTPIN (-700 900) $PN 1
J 0
(-690 880);
DISPLAY 0.617021 (-690 880);
PAINT ORANGE (-690 880);
FORCEPROP 1 LAST PACK_TYPE 0603V
J 0
(-650 600);
DISPLAY 0.617021 (-650 600);
PAINT SKYBLUE (-650 600);
FORCEPROP 1 LAST PART_NUMBER E15431-004
J 0
(-650 650);
DISPLAY 0.617021 (-650 650);
PAINT BLUE (-650 650);
FORCEPROP 1 LAST VOLTAGE 4V
J 0
(-650 800);
DISPLAY 0.617021 (-650 800);
PAINT SKYBLUE (-650 800);
FORCEPROP 1 LAST TOLERANCE 20%
J 0
(-650 750);
DISPLAY 0.617021 (-650 750);
PAINT SKYBLUE (-650 750);
FORCEPROP 1 LAST MATERIAL X6S
J 0
(-650 700);
DISPLAY 0.617021 (-650 700);
PAINT SKYBLUE (-650 700);
FORCEPROP 0 LAST GROUP PWR_MLCC_CAP
J 0
(-644 562);
DISPLAY 0.638298 (-644 562);
PAINT BROWN (-644 562);
DISPLAY BOTH (-644 562);
FORCEPROP 2 LAST SEC_TYPE 0603V
J 0
(-645 1000);
DISPLAY 1.021277 (-645 1000);
PAINT ORANGE (-645 1000);
DISPLAY INVISIBLE (-645 1000);
FORCEPROP 2 LAST SEC 1
J 0
(-645 1000);
DISPLAY 0.680851 (-645 1000);
PAINT MONO (-645 1000);
DISPLAY INVISIBLE (-645 1000);
FORCEPROP 2 LAST BOM_COST PROC_VRD_VCCIN_CPU0
J 0
(-650 950);
DISPLAY 1.446809 (-650 950);
PAINT MONO (-650 950);
DISPLAY INVISIBLE (-650 950);
FORCEPROP 2 LAST CDS_LOCATION C1D3
J 0
(-650 900);
DISPLAY 0.617021 (-650 900);
PAINT AQUA (-650 900);
DISPLAY INVISIBLE (-650 900);
FORCEPROP 2 LAST CDS_SEC 1
J 0
(-650 950);
PAINT ORANGE (-650 950);
DISPLAY INVISIBLE (-650 950);
FORCEPROP 1 LAST PATH I22
J 0
(-650 950);
DISPLAY 0.978723 (-650 950);
PAINT WHITE (-650 950);
DISPLAY INVISIBLE (-650 950);
FORCEPROP 2 LAST ROOM PVCCIN_CPU1_PWR_VR
J 0
(-650 950);
DISPLAY 1.446809 (-650 950);
PAINT MONO (-650 950);
DISPLAY INVISIBLE (-650 950);
FORCEPROP 2 LAST CDS_LIB dev_discrete
J 0
(-700 800);
PAINT ORANGE (-700 800);
DISPLAY INVISIBLE (-700 800);
FORCEADD GND..1
(-2600 3175);
FORCEPROP 3 LASTPIN (-2600 3225) SIG_NAME GND\g
J 0
(-2590 3235);
DISPLAY 0.659574 (-2590 3235);
PAINT MONO (-2590 3235);
DISPLAY INVISIBLE (-2590 3235);
FORCEPROP 1 LAST HDL_POWER GND
J 0
(-2600 3325);
DISPLAY 1.723404 (-2600 3325);
PAINT GREEN (-2600 3325);
DISPLAY INVISIBLE (-2600 3325);
FORCEPROP 1 LAST BODY_TYPE PLUMBING
J 0
(-2645 3132);
DISPLAY 0.340426 (-2645 3132);
PAINT GREEN (-2645 3132);
DISPLAY INVISIBLE (-2645 3132);
FORCEPROP 1 LAST SIZE 1B
J 0
(-2525 3125);
DISPLAY 1.723404 (-2525 3125);
PAINT GREEN (-2525 3125);
DISPLAY INVISIBLE (-2525 3125);
FORCEPROP 1 LAST PATH I23
J 0
(-2525 3175);
DISPLAY 0.872340 (-2525 3175);
PAINT AQUA (-2525 3175);
DISPLAY INVISIBLE (-2525 3175);
FORCEPROP 1 LAST VOLTAGE 0
J 0
(-2600 3175);
PAINT SKYBLUE (-2600 3175);
DISPLAY INVISIBLE (-2600 3175);
FORCEPROP 2 LAST CDS_LIB mstr_symbols
J 0
(-2600 3175);
DISPLAY 1.936170 (-2600 3175);
PAINT ORANGE (-2600 3175);
DISPLAY INVISIBLE (-2600 3175);
FORCEPROP 2 LAST BOM_COST PROC_VRD_VCCIN_CPU0
J 0
(-2975 3250);
DISPLAY 1.446809 (-2975 3250);
PAINT MONO (-2975 3250);
DISPLAY INVISIBLE (-2975 3250);
FORCEPROP 2 LAST ROOM PVCCIN_CPU1_PWR_VR
J 0
(-3150 3250);
DISPLAY 1.936170 (-3150 3250);
PAINT ORANGE (-3150 3250);
DISPLAY INVISIBLE (-3150 3250);
FORCEADD CAPP..1
(-2375 2650);
FORCEPROP 1 LAST MATERIAL ALUM
J 0
(-2325 2550);
DISPLAY 0.617021 (-2325 2550);
PAINT SKYBLUE (-2325 2550);
FORCEPROP 1 LAST PART_NUMBER 699013-049
J 0
(-2325 2450);
DISPLAY 0.617021 (-2325 2450);
PAINT BLUE (-2325 2450);
FORCEPROP 1 LAST VOLTAGE 2.5V
J 0
(-2325 2600);
DISPLAY 0.638298 (-2325 2600);
PAINT SKYBLUE (-2325 2600);
FORCEPROP 1 LAST TOLERANCE 20%
J 0
(-2325 2650);
DISPLAY 0.617021 (-2325 2650);
PAINT SKYBLUE (-2325 2650);
FORCEPROP 1 LAST VALUE 470UF
J 0
(-2325 2700);
DISPLAY 0.617021 (-2325 2700);
PAINT SKYBLUE (-2325 2700);
FORCEPROP 1 LAST LOCATION C9N24
J 0
(-2325 2750);
DISPLAY 0.617021 (-2325 2750);
PAINT AQUA (-2325 2750);
FORCEPROP 1 LASTPIN (-2375 2550) $PN 2
J 0
(-2365 2535);
DISPLAY 0.617021 (-2365 2535);
PAINT GREEN (-2365 2535);
FORCEPROP 1 LASTPIN (-2375 2750) $PN 1
J 0
(-2365 2735);
DISPLAY 0.617021 (-2365 2735);
PAINT GREEN (-2365 2735);
FORCEPROP 1 LAST PACK_TYPE 3018
J 0
(-2325 2500);
DISPLAY 0.617021 (-2325 2500);
PAINT SKYBLUE (-2325 2500);
FORCEPROP 0 LAST GROUP PWR_BULK_CAP
J 0
(-2329 2401);
DISPLAY 0.638298 (-2329 2401);
PAINT BROWN (-2329 2401);
DISPLAY BOTH (-2329 2401);
FORCEPROP 2 LAST CDS_LIB mstr_discrete
J 0
(-2375 2650);
PAINT MONO (-2375 2650);
DISPLAY INVISIBLE (-2375 2650);
FORCEPROP 2 LAST ROOM PVCCIN_CPU1_DECAP_VR
J 0
(-2325 2775);
PAINT MONO (-2325 2775);
DISPLAY INVISIBLE (-2325 2775);
FORCEPROP 1 LAST PATH I24
J 0
(-2325 2800);
DISPLAY 0.978723 (-2325 2800);
PAINT ORANGE (-2325 2800);
DISPLAY INVISIBLE (-2325 2800);
FORCEPROP 2 LAST CDS_LOCATION C9N24
J 0
(-2325 2750);
DISPLAY 0.617021 (-2325 2750);
PAINT AQUA (-2325 2750);
DISPLAY INVISIBLE (-2325 2750);
FORCEPROP 2 LAST BOM_COST PROC_VRD_VCCIN_CPU0
J 0
(-2325 2800);
PAINT MONO (-2325 2800);
DISPLAY INVISIBLE (-2325 2800);
FORCEPROP 2 LAST SEC 1
J 0
(-2325 2850);
PAINT MONO (-2325 2850);
DISPLAY INVISIBLE (-2325 2850);
FORCEPROP 2 LAST SEC_TYPE 3018
J 0
(-2310 2860);
DISPLAY 1.021277 (-2310 2860);
PAINT ORANGE (-2310 2860);
DISPLAY INVISIBLE (-2310 2860);
FORCEADD CAPP..1
(-2825 2650);
FORCEPROP 1 LAST PART_NUMBER 699013-049
J 0
(-2775 2450);
DISPLAY 0.617021 (-2775 2450);
PAINT BLUE (-2775 2450);
FORCEPROP 1 LAST VALUE 470UF
J 0
(-2775 2700);
DISPLAY 0.617021 (-2775 2700);
PAINT SKYBLUE (-2775 2700);
FORCEPROP 1 LAST VOLTAGE 2.5V
J 0
(-2775 2600);
DISPLAY 0.638298 (-2775 2600);
PAINT SKYBLUE (-2775 2600);
FORCEPROP 1 LAST LOCATION C9R9
J 0
(-2775 2750);
DISPLAY 0.617021 (-2775 2750);
PAINT AQUA (-2775 2750);
FORCEPROP 1 LASTPIN (-2825 2750) $PN 1
J 0
(-2815 2735);
DISPLAY 0.617021 (-2815 2735);
PAINT GREEN (-2815 2735);
FORCEPROP 1 LASTPIN (-2825 2550) $PN 2
J 0
(-2815 2535);
DISPLAY 0.617021 (-2815 2535);
PAINT GREEN (-2815 2535);
FORCEPROP 1 LAST TOLERANCE 20%
J 0
(-2775 2650);
DISPLAY 0.617021 (-2775 2650);
PAINT SKYBLUE (-2775 2650);
FORCEPROP 1 LAST MATERIAL ALUM
J 0
(-2775 2550);
DISPLAY 0.617021 (-2775 2550);
PAINT SKYBLUE (-2775 2550);
FORCEPROP 1 LAST PACK_TYPE 3018
J 0
(-2775 2500);
DISPLAY 0.617021 (-2775 2500);
PAINT SKYBLUE (-2775 2500);
FORCEPROP 0 LAST GROUP PWR_BULK_CAP
J 0
(-2779 2401);
DISPLAY 0.638298 (-2779 2401);
PAINT BROWN (-2779 2401);
DISPLAY BOTH (-2779 2401);
FORCEPROP 2 LAST CDS_LIB mstr_discrete
J 0
(-2825 2650);
PAINT MONO (-2825 2650);
DISPLAY INVISIBLE (-2825 2650);
FORCEPROP 2 LAST CDS_LOCATION C9R9
J 0
(-2775 2750);
DISPLAY 0.617021 (-2775 2750);
PAINT AQUA (-2775 2750);
DISPLAY INVISIBLE (-2775 2750);
FORCEPROP 1 LAST PATH I25
J 0
(-2775 2800);
DISPLAY 0.978723 (-2775 2800);
PAINT ORANGE (-2775 2800);
DISPLAY INVISIBLE (-2775 2800);
FORCEPROP 2 LAST ROOM PVCCIN_CPU1_DECAP_VR
J 0
(-2775 2775);
PAINT MONO (-2775 2775);
DISPLAY INVISIBLE (-2775 2775);
FORCEPROP 2 LAST BOM_COST PROC_VRD_VCCIN_CPU0
J 0
(-2775 2800);
PAINT MONO (-2775 2800);
DISPLAY INVISIBLE (-2775 2800);
FORCEPROP 2 LAST SEC_TYPE 3018
J 0
(-2760 2860);
DISPLAY 1.021277 (-2760 2860);
PAINT ORANGE (-2760 2860);
DISPLAY INVISIBLE (-2760 2860);
FORCEPROP 2 LAST SEC 1
J 0
(-2775 2850);
PAINT MONO (-2775 2850);
DISPLAY INVISIBLE (-2775 2850);
FORCEADD CAPP..1
(-3275 2650);
FORCEPROP 1 LAST PART_NUMBER 699013-049
J 0
(-3225 2450);
DISPLAY 0.617021 (-3225 2450);
PAINT BLUE (-3225 2450);
FORCEPROP 1 LASTPIN (-3275 2550) $PN 2
J 0
(-3265 2535);
DISPLAY 0.617021 (-3265 2535);
PAINT GREEN (-3265 2535);
FORCEPROP 1 LAST LOCATION C9R3
J 0
(-3225 2750);
DISPLAY 0.617021 (-3225 2750);
PAINT AQUA (-3225 2750);
FORCEPROP 1 LAST PACK_TYPE 3018
J 0
(-3225 2500);
DISPLAY 0.617021 (-3225 2500);
PAINT SKYBLUE (-3225 2500);
FORCEPROP 1 LAST MATERIAL ALUM
J 0
(-3225 2550);
DISPLAY 0.617021 (-3225 2550);
PAINT SKYBLUE (-3225 2550);
FORCEPROP 1 LAST VOLTAGE 2.5V
J 0
(-3225 2600);
DISPLAY 0.638298 (-3225 2600);
PAINT SKYBLUE (-3225 2600);
FORCEPROP 1 LASTPIN (-3275 2750) $PN 1
J 0
(-3265 2735);
DISPLAY 0.617021 (-3265 2735);
PAINT GREEN (-3265 2735);
FORCEPROP 1 LAST VALUE 470UF
J 0
(-3225 2700);
DISPLAY 0.617021 (-3225 2700);
PAINT SKYBLUE (-3225 2700);
FORCEPROP 1 LAST TOLERANCE 20%
J 0
(-3225 2650);
DISPLAY 0.617021 (-3225 2650);
PAINT SKYBLUE (-3225 2650);
FORCEPROP 0 LAST GROUP PWR_BULK_CAP
J 0
(-3229 2401);
DISPLAY 0.638298 (-3229 2401);
PAINT BROWN (-3229 2401);
DISPLAY BOTH (-3229 2401);
FORCEPROP 2 LAST CDS_LIB mstr_discrete
J 0
(-3275 2650);
PAINT MONO (-3275 2650);
DISPLAY INVISIBLE (-3275 2650);
FORCEPROP 2 LAST ROOM PVCCIN_CPU1_DECAP_VR
J 0
(-3225 2775);
PAINT MONO (-3225 2775);
DISPLAY INVISIBLE (-3225 2775);
FORCEPROP 1 LAST PATH I26
J 0
(-3225 2800);
DISPLAY 0.978723 (-3225 2800);
PAINT ORANGE (-3225 2800);
DISPLAY INVISIBLE (-3225 2800);
FORCEPROP 2 LAST CDS_LOCATION C9R3
J 0
(-3225 2750);
DISPLAY 0.617021 (-3225 2750);
PAINT AQUA (-3225 2750);
DISPLAY INVISIBLE (-3225 2750);
FORCEPROP 2 LAST BOM_COST PROC_VRD_VCCIN_CPU0
J 0
(-3225 2800);
PAINT MONO (-3225 2800);
DISPLAY INVISIBLE (-3225 2800);
FORCEPROP 2 LAST SEC 1
J 0
(-3225 2850);
PAINT MONO (-3225 2850);
DISPLAY INVISIBLE (-3225 2850);
FORCEPROP 2 LAST SEC_TYPE 3018
J 0
(-3210 2860);
DISPLAY 1.021277 (-3210 2860);
PAINT ORANGE (-3210 2860);
DISPLAY INVISIBLE (-3210 2860);
FORCEADD IR354XX..1
(-3300 3875);
FORCEPROP 2 LASTPIN (-2800 3925) $PN 36
J 0
(-2790 3935);
DISPLAY 0.617021 (-2790 3935);
PAINT ORANGE (-2790 3935);
FORCEPROP 2 LASTPIN (-3800 3525) $PN 32
J 2
(-3810 3535);
DISPLAY 0.617021 (-3810 3535);
PAINT ORANGE (-3810 3535);
FORCEPROP 2 LASTPIN (-2800 4425) $PN 38
J 0
(-2790 4435);
DISPLAY 0.617021 (-2790 4435);
PAINT ORANGE (-2790 4435);
FORCEPROP 2 LASTPIN (-3800 4425) $PN 3
J 2
(-3810 4435);
DISPLAY 0.617021 (-3810 4435);
PAINT ORANGE (-3810 4435);
FORCEPROP 2 LASTPIN (-3800 4225) $PN 4
J 2
(-3810 4235);
DISPLAY 0.617021 (-3810 4235);
PAINT ORANGE (-3810 4235);
FORCEPROP 2 LASTPIN (-3800 4325) $PN 25
J 2
(-3810 4335);
DISPLAY 0.617021 (-3810 4335);
PAINT ORANGE (-3810 4335);
FORCEPROP 2 LASTPIN (-3800 4375) $PN 30
J 2
(-3810 4385);
DISPLAY 0.617021 (-3810 4385);
PAINT ORANGE (-3810 4385);
FORCEPROP 2 LASTPIN (-2800 3575) $PN 10
J 0
(-2790 3585);
DISPLAY 0.617021 (-2790 3585);
PAINT ORANGE (-2790 3585);
FORCEPROP 2 LASTPIN (-2800 3475) $PN 2
J 0
(-2790 3485);
DISPLAY 0.617021 (-2790 3485);
PAINT ORANGE (-2790 3485);
FORCEPROP 2 LASTPIN (-2800 3325) $PN 5
J 0
(-2790 3335);
DISPLAY 0.617021 (-2790 3335);
PAINT ORANGE (-2790 3335);
FORCEPROP 2 LASTPIN (-3800 3875) $PN 6
J 2
(-3810 3885);
DISPLAY 0.617021 (-3810 3885);
PAINT ORANGE (-3810 3885);
FORCEPROP 2 LASTPIN (-3800 4025) $PN 1
J 2
(-3810 4035);
DISPLAY 0.617021 (-3810 4035);
PAINT ORANGE (-3810 4035);
FORCEPROP 2 LASTPIN (-3800 3925) $PN 41
J 2
(-3810 3935);
DISPLAY 0.617021 (-3810 3935);
PAINT ORANGE (-3810 3935);
FORCEPROP 2 LASTPIN (-3800 3675) $PN 39
J 2
(-3810 3685);
DISPLAY 0.617021 (-3810 3685);
PAINT ORANGE (-3810 3685);
FORCEPROP 2 LASTPIN (-3800 3575) $PN 33
J 2
(-3810 3585);
DISPLAY 0.617021 (-3810 3585);
PAINT ORANGE (-3810 3585);
FORCEPROP 2 LASTPIN (-2800 4175) $PN 31
J 0
(-2790 4185);
DISPLAY 0.617021 (-2790 4185);
PAINT ORANGE (-2790 4185);
FORCEPROP 2 LASTPIN (-2800 3425) $PN 40
J 0
(-2790 3435);
DISPLAY 0.617021 (-2790 3435);
PAINT ORANGE (-2790 3435);
FORCEPROP 2 LASTPIN (-2800 3375) $PN 7
J 0
(-2790 3385);
DISPLAY 0.617021 (-2790 3385);
PAINT ORANGE (-2790 3385);
FORCEPROP 2 LASTPIN (-3800 4125) $PN 35
J 2
(-3810 4135);
DISPLAY 0.617021 (-3810 4135);
PAINT ORANGE (-3810 4135);
FORCEPROP 2 LASTPIN (-3800 3775) $PN 34
J 2
(-3810 3785);
DISPLAY 0.617021 (-3810 3785);
PAINT ORANGE (-3810 3785);
FORCEPROP 1 LAST PART_NUMBER H73688-001
J 0
(-3650 3175);
DISPLAY 0.617021 (-3650 3175);
PAINT BLUE (-3650 3175);
FORCEPROP 2 LASTPIN (-2800 4225) $PN 37
J 0
(-2790 4235);
DISPLAY 0.617021 (-2790 4235);
PAINT ORANGE (-2790 4235);
FORCEPROP 1 LAST MATERIAL IC
J 0
(-3750 4625);
DISPLAY 0.617021 (-3750 4625);
PAINT SKYBLUE (-3750 4625);
FORCEPROP 1 LAST LOCATION EU1D3
J 0
(-3525 4675);
DISPLAY 0.617021 (-3525 4675);
PAINT AQUA (-3525 4675);
FORCEPROP 2 LAST SEC 1
J 0
(-3300 4675);
DISPLAY 0.680851 (-3300 4675);
PAINT MONO (-3300 4675);
DISPLAY INVISIBLE (-3300 4675);
FORCEPROP 2 LAST SEC_TYPE SM
J 0
(-3300 4675);
DISPLAY 1.021277 (-3300 4675);
PAINT ORANGE (-3300 4675);
DISPLAY INVISIBLE (-3300 4675);
FORCEPROP 2 LAST CDS_LOCATION EU1D3
J 0
(-3525 4675);
DISPLAY 0.617021 (-3525 4675);
PAINT AQUA (-3525 4675);
DISPLAY INVISIBLE (-3525 4675);
FORCEPROP 1 LAST PATH I27
J 0
(-3300 4625);
PAINT GREEN (-3300 4625);
DISPLAY INVISIBLE (-3300 4625);
FORCEPROP 1 LAST PACK_TYPE SM
J 0
(-3750 4725);
PAINT SKYBLUE (-3750 4725);
DISPLAY INVISIBLE (-3750 4725);
FORCEPROP 2 LAST CDS_LIB mstr_discrete
J 0
(-3300 3875);
PAINT ORANGE (-3300 3875);
DISPLAY INVISIBLE (-3300 3875);
FORCEPROP 2 LAST ROOM PVCCIN_CPU1_PWR_VR
J 0
(-5025 2150);
DISPLAY 1.361702 (-5025 2150);
PAINT ORANGE (-5025 2150);
DISPLAY INVISIBLE (-5025 2150);
FORCEPROP 1 LAST VALUE IR35411
J 1
(-3300 4500);
DISPLAY 0.617021 (-3300 4500);
PAINT SKYBLUE (-3300 4500);
DISPLAY INVISIBLE (-3300 4500);
FORCEADD CAPP..1
(-3725 2650);
FORCEPROP 1 LAST TOLERANCE 20%
J 0
(-3675 2650);
DISPLAY 0.617021 (-3675 2650);
PAINT SKYBLUE (-3675 2650);
FORCEPROP 1 LAST VOLTAGE 2.5V
J 0
(-3675 2600);
DISPLAY 0.638298 (-3675 2600);
PAINT SKYBLUE (-3675 2600);
FORCEPROP 1 LASTPIN (-3725 2750) $PN 1
J 0
(-3715 2735);
DISPLAY 0.617021 (-3715 2735);
PAINT GREEN (-3715 2735);
FORCEPROP 1 LAST VALUE 470UF
J 0
(-3675 2700);
DISPLAY 0.617021 (-3675 2700);
PAINT SKYBLUE (-3675 2700);
FORCEPROP 1 LASTPIN (-3725 2550) $PN 2
J 0
(-3715 2535);
DISPLAY 0.617021 (-3715 2535);
PAINT GREEN (-3715 2535);
FORCEPROP 1 LAST LOCATION C9P23
J 0
(-3675 2750);
DISPLAY 0.617021 (-3675 2750);
PAINT AQUA (-3675 2750);
FORCEPROP 1 LAST PART_NUMBER 699013-049
J 0
(-3675 2450);
DISPLAY 0.617021 (-3675 2450);
PAINT BLUE (-3675 2450);
FORCEPROP 1 LAST PACK_TYPE 3018
J 0
(-3675 2500);
DISPLAY 0.617021 (-3675 2500);
PAINT SKYBLUE (-3675 2500);
FORCEPROP 1 LAST MATERIAL ALUM
J 0
(-3675 2550);
DISPLAY 0.617021 (-3675 2550);
PAINT SKYBLUE (-3675 2550);
FORCEPROP 0 LAST GROUP PWR_BULK_CAP
J 0
(-3679 2401);
DISPLAY 0.638298 (-3679 2401);
PAINT BROWN (-3679 2401);
DISPLAY BOTH (-3679 2401);
FORCEPROP 2 LAST CDS_LIB mstr_discrete
J 0
(-3725 2650);
PAINT MONO (-3725 2650);
DISPLAY INVISIBLE (-3725 2650);
FORCEPROP 2 LAST ROOM PVCCIN_CPU1_DECAP_VR
J 0
(-3675 2775);
PAINT MONO (-3675 2775);
DISPLAY INVISIBLE (-3675 2775);
FORCEPROP 1 LAST PATH I28
J 0
(-3675 2800);
DISPLAY 0.978723 (-3675 2800);
PAINT ORANGE (-3675 2800);
DISPLAY INVISIBLE (-3675 2800);
FORCEPROP 2 LAST CDS_LOCATION C9P23
J 0
(-3675 2750);
DISPLAY 0.617021 (-3675 2750);
PAINT AQUA (-3675 2750);
DISPLAY INVISIBLE (-3675 2750);
FORCEPROP 2 LAST BOM_COST PROC_VRD_VCCIN_CPU0
J 0
(-3675 2800);
PAINT MONO (-3675 2800);
DISPLAY INVISIBLE (-3675 2800);
FORCEPROP 2 LAST SEC 1
J 0
(-3675 2850);
PAINT MONO (-3675 2850);
DISPLAY INVISIBLE (-3675 2850);
FORCEPROP 2 LAST SEC_TYPE 3018
J 0
(-3660 2860);
DISPLAY 1.021277 (-3660 2860);
PAINT ORANGE (-3660 2860);
DISPLAY INVISIBLE (-3660 2860);
FORCEADD PVCCIN_CPU1..1
(-4250 2900);
FORCEPROP 3 LASTPIN (-4250 2850) SIG_NAME PVCCIN_CPU1\g
J 0
(-4240 2860);
DISPLAY 0.659574 (-4240 2860);
PAINT MONO (-4240 2860);
DISPLAY INVISIBLE (-4240 2860);
FORCEPROP 1 LAST HDL_POWER PVCCIN_CPU1
J 1
(-4250 2950);
DISPLAY 0.872340 (-4250 2950);
PAINT GREEN (-4250 2950);
DISPLAY INVISIBLE (-4250 2950);
FORCEPROP 1 LAST BODY_TYPE PLUMBING
J 0
(-4295 2857);
DISPLAY 0.340426 (-4295 2857);
PAINT GREEN (-4295 2857);
DISPLAY INVISIBLE (-4295 2857);
FORCEPROP 1 LAST PATH I29
J 0
(-4200 2925);
DISPLAY 0.872340 (-4200 2925);
PAINT AQUA (-4200 2925);
DISPLAY INVISIBLE (-4200 2925);
FORCEPROP 2 LAST CDS_LIB mstr_symbols
J 0
(-4250 2900);
PAINT ORANGE (-4250 2900);
DISPLAY INVISIBLE (-4250 2900);
FORCEPROP 1 LAST VOLTAGE 2.0V
J 0
(-4295 2857);
DISPLAY 0.340426 (-4295 2857);
PAINT SKYBLUE (-4295 2857);
DISPLAY INVISIBLE (-4295 2857);
FORCEADD OFFPAGE..2
(-1525 4050);
FORCEPROP 2 LAST $XR3 206 
J 0
(-976 4050);
DISPLAY 0.638298 (-976 4050);
PAINT MONO (-976 4050);
FORCEPROP 2 LAST $XR2 209 
J 0
(-1096 4050);
DISPLAY 0.638298 (-1096 4050);
PAINT MONO (-1096 4050);
FORCEPROP 2 LAST $XR1 208 
J 0
(-1216 4050);
DISPLAY 0.638298 (-1216 4050);
PAINT MONO (-1216 4050);
FORCEPROP 2 LAST $XR0 207 
J 0
(-1336 4050);
DISPLAY 0.638298 (-1336 4050);
PAINT MONO (-1336 4050);
FORCEPROP 1 LAST COMMENT_BODY TRUE
J 0
(-1570 3955);
DISPLAY 1.723404 (-1570 3955);
PAINT GREEN (-1570 3955);
DISPLAY INVISIBLE (-1570 3955);
FORCEPROP 1 LAST OFFPAGE TRUE
J 0
(-1200 3925);
DISPLAY 1.723404 (-1200 3925);
PAINT GREEN (-1200 3925);
DISPLAY INVISIBLE (-1200 3925);
FORCEPROP 2 LAST ROOM PVCCIN_CPU1_PWR_VR
J 0
(-1925 4125);
DISPLAY 1.936170 (-1925 4125);
PAINT ORANGE (-1925 4125);
DISPLAY INVISIBLE (-1925 4125);
FORCEPROP 2 LAST CDS_LIB mstr_standard
J 0
(-1525 4050);
PAINT ORANGE (-1525 4050);
DISPLAY INVISIBLE (-1525 4050);
FORCEPROP 2 LAST BOM_COST PROC_VRD_VCCIN_CPU0
J 0
(-1325 4100);
DISPLAY 1.446809 (-1325 4100);
PAINT MONO (-1325 4100);
DISPLAY INVISIBLE (-1325 4100);
FORCEPROP 2 LAST PATH I3
J 0
(-1095 4100);
DISPLAY 1.021277 (-1095 4100);
PAINT ORANGE (-1095 4100);
DISPLAY INVISIBLE (-1095 4100);
FORCEADD CAPP..1
(-4250 2650);
FORCEPROP 1 LAST VOLTAGE 2.5V
J 0
(-4200 2600);
DISPLAY 0.617021 (-4200 2600);
PAINT SKYBLUE (-4200 2600);
FORCEPROP 1 LAST TOLERANCE 20%
J 0
(-4200 2650);
DISPLAY 0.617021 (-4200 2650);
PAINT SKYBLUE (-4200 2650);
FORCEPROP 1 LASTPIN (-4250 2550) $PN 2
J 0
(-4240 2535);
DISPLAY 0.617021 (-4240 2535);
PAINT GREEN (-4240 2535);
FORCEPROP 1 LASTPIN (-4250 2750) $PN 1
J 0
(-4240 2735);
DISPLAY 0.617021 (-4240 2735);
PAINT GREEN (-4240 2735);
FORCEPROP 1 LAST VALUE 470UF
J 0
(-4200 2700);
DISPLAY 0.617021 (-4200 2700);
PAINT SKYBLUE (-4200 2700);
FORCEPROP 1 LAST LOCATION C9P18
J 0
(-4200 2750);
DISPLAY 0.617021 (-4200 2750);
PAINT AQUA (-4200 2750);
FORCEPROP 1 LAST MATERIAL ALUM
J 0
(-4200 2550);
DISPLAY 0.617021 (-4200 2550);
PAINT SKYBLUE (-4200 2550);
FORCEPROP 1 LAST PACK_TYPE 3018
J 0
(-4200 2500);
DISPLAY 0.617021 (-4200 2500);
PAINT SKYBLUE (-4200 2500);
FORCEPROP 1 LAST PART_NUMBER 699013-049
J 0
(-4200 2450);
DISPLAY 0.617021 (-4200 2450);
PAINT BLUE (-4200 2450);
FORCEPROP 0 LAST GROUP PWR_BULK_CAP
J 0
(-4204 2401);
DISPLAY 0.638298 (-4204 2401);
PAINT BROWN (-4204 2401);
DISPLAY BOTH (-4204 2401);
FORCEPROP 2 LAST SEC_TYPE 3018
J 0
(-4185 2860);
DISPLAY 1.021277 (-4185 2860);
PAINT ORANGE (-4185 2860);
DISPLAY INVISIBLE (-4185 2860);
FORCEPROP 2 LAST SEC 1
J 0
(-4200 2850);
PAINT MONO (-4200 2850);
DISPLAY INVISIBLE (-4200 2850);
FORCEPROP 2 LAST BOM_COST PROC_VRD_VCCIN_CPU0
J 0
(-4200 2800);
PAINT MONO (-4200 2800);
DISPLAY INVISIBLE (-4200 2800);
FORCEPROP 2 LAST CDS_LOCATION C9P18
J 0
(-4200 2750);
DISPLAY 0.617021 (-4200 2750);
PAINT AQUA (-4200 2750);
DISPLAY INVISIBLE (-4200 2750);
FORCEPROP 1 LAST PATH I30
J 0
(-4200 2800);
DISPLAY 0.978723 (-4200 2800);
PAINT ORANGE (-4200 2800);
DISPLAY INVISIBLE (-4200 2800);
FORCEPROP 2 LAST ROOM PVCCIN_CPU1_DECAP_VR
J 0
(-4200 2775);
PAINT MONO (-4200 2775);
DISPLAY INVISIBLE (-4200 2775);
FORCEPROP 2 LAST CDS_LIB mstr_discrete
J 0
(-4250 2650);
PAINT MONO (-4250 2650);
DISPLAY INVISIBLE (-4250 2650);
FORCEADD GND..1
(-2575 600);
FORCEPROP 3 LASTPIN (-2575 650) SIG_NAME GND\g
J 0
(-2565 660);
DISPLAY 0.659574 (-2565 660);
PAINT MONO (-2565 660);
DISPLAY INVISIBLE (-2565 660);
FORCEPROP 1 LAST HDL_POWER GND
J 0
(-2575 750);
DISPLAY 1.723404 (-2575 750);
PAINT GREEN (-2575 750);
DISPLAY INVISIBLE (-2575 750);
FORCEPROP 1 LAST BODY_TYPE PLUMBING
J 0
(-2620 557);
DISPLAY 0.340426 (-2620 557);
PAINT GREEN (-2620 557);
DISPLAY INVISIBLE (-2620 557);
FORCEPROP 1 LAST SIZE 1B
J 0
(-2500 550);
DISPLAY 1.723404 (-2500 550);
PAINT GREEN (-2500 550);
DISPLAY INVISIBLE (-2500 550);
FORCEPROP 1 LAST PATH I33
J 0
(-2500 600);
DISPLAY 0.872340 (-2500 600);
PAINT AQUA (-2500 600);
DISPLAY INVISIBLE (-2500 600);
FORCEPROP 1 LAST VOLTAGE 0
J 0
(-2575 600);
PAINT SKYBLUE (-2575 600);
DISPLAY INVISIBLE (-2575 600);
FORCEPROP 2 LAST CDS_LIB mstr_symbols
J 0
(-2575 600);
PAINT ORANGE (-2575 600);
DISPLAY INVISIBLE (-2575 600);
FORCEPROP 2 LAST BOM_COST PROC_VRD_VCCIN_CPU0
J 0
(-2950 675);
DISPLAY 1.446809 (-2950 675);
PAINT MONO (-2950 675);
DISPLAY INVISIBLE (-2950 675);
FORCEPROP 2 LAST ROOM PVCCIN_CPU1_PWR_VR
J 0
(-3125 675);
DISPLAY 1.936170 (-3125 675);
PAINT ORANGE (-3125 675);
DISPLAY INVISIBLE (-3125 675);
FORCEADD VCC_CORE..1
(-6625 4575);
FORCEPROP 3 LASTPIN (-6625 4525) SIG_NAME VR_FET_SW_P12V_STBY_PVCCIN_CPU1\g
J 0
(-6615 4535);
DISPLAY 0.659574 (-6615 4535);
PAINT MONO (-6615 4535);
DISPLAY INVISIBLE (-6615 4535);
FORCEPROP 1 LAST HDL_POWER VR_FET_SW_P12V_STBY_PVCCIN_CPU1
J 1
(-6525 4625);
DISPLAY 0.617021 (-6525 4625);
PAINT GREEN (-6525 4625);
FORCEPROP 2 LAST CDS_LIB mstr_symbols
J 0
(-6625 4575);
DISPLAY 1.936170 (-6625 4575);
PAINT ORANGE (-6625 4575);
DISPLAY INVISIBLE (-6625 4575);
FORCEPROP 1 LAST PATH I37
J 0
(-6575 4600);
DISPLAY 0.872340 (-6575 4600);
PAINT AQUA (-6575 4600);
DISPLAY INVISIBLE (-6575 4600);
FORCEADD CAP..1
(-4775 4200);
FORCEPROP 1 LAST PART_NUMBER A36096-155
J 0
(-4575 4250);
DISPLAY 0.617021 (-4575 4250);
PAINT BLUE (-4575 4250);
FORCEPROP 1 LAST PACK_TYPE 0402
J 0
(-4575 4200);
DISPLAY 0.617021 (-4575 4200);
PAINT SKYBLUE (-4575 4200);
FORCEPROP 1 LAST TOLERANCE 10%
J 0
(-4725 4150);
DISPLAY 0.617021 (-4725 4150);
PAINT SKYBLUE (-4725 4150);
FORCEPROP 1 LAST MATERIAL X7R
J 0
(-4575 4300);
DISPLAY 0.617021 (-4575 4300);
PAINT SKYBLUE (-4575 4300);
FORCEPROP 1 LASTPIN (-4775 4100) $PN 2
J 0
(-4765 4080);
DISPLAY 0.617021 (-4765 4080);
PAINT ORANGE (-4765 4080);
FORCEPROP 1 LASTPIN (-4775 4300) $PN 1
J 0
(-4765 4280);
DISPLAY 0.617021 (-4765 4280);
PAINT ORANGE (-4765 4280);
FORCEPROP 1 LAST LOCATION C1D16
J 0
(-4725 4300);
DISPLAY 0.617021 (-4725 4300);
PAINT AQUA (-4725 4300);
FORCEPROP 1 LAST VALUE 0.22UF
J 0
(-4725 4250);
DISPLAY 0.617021 (-4725 4250);
PAINT SKYBLUE (-4725 4250);
FORCEPROP 1 LAST VOLTAGE 16V
J 0
(-4725 4200);
DISPLAY 0.617021 (-4725 4200);
PAINT SKYBLUE (-4725 4200);
FORCEPROP 2 LAST CDS_LIB mstr_discrete
J 0
(-4775 4200);
PAINT ORANGE (-4775 4200);
DISPLAY INVISIBLE (-4775 4200);
FORCEPROP 2 LAST CDS_LOCATION C1D16
J 0
(-4725 4300);
DISPLAY 0.617021 (-4725 4300);
PAINT AQUA (-4725 4300);
DISPLAY INVISIBLE (-4725 4300);
FORCEPROP 1 LAST PATH I38
J 0
(-4725 4350);
DISPLAY 0.978723 (-4725 4350);
PAINT WHITE (-4725 4350);
DISPLAY INVISIBLE (-4725 4350);
FORCEPROP 2 LAST ROOM PVCCIN_CPU1_PWR_VR
J 0
(-4725 4350);
DISPLAY 1.361702 (-4725 4350);
PAINT ORANGE (-4725 4350);
DISPLAY INVISIBLE (-4725 4350);
FORCEPROP 2 LAST SEC_TYPE 0402
J 0
(-4725 4400);
DISPLAY 1.021277 (-4725 4400);
PAINT ORANGE (-4725 4400);
DISPLAY INVISIBLE (-4725 4400);
FORCEPROP 2 LAST SEC 1
J 0
(-4725 4400);
DISPLAY 0.680851 (-4725 4400);
PAINT MONO (-4725 4400);
DISPLAY INVISIBLE (-4725 4400);
FORCEADD CAP..1
R 2
(-5975 3575);
FORCEPROP 1 LASTPIN (-5975 3675) $PN 1
J 2
(-5985 3655);
DISPLAY 0.617021 (-5985 3655);
PAINT ORANGE (-5985 3655);
FORCEPROP 1 LAST LOCATION C1D20
J 2
(-6025 3675);
DISPLAY 0.617021 (-6025 3675);
PAINT AQUA (-6025 3675);
FORCEPROP 1 LAST VALUE 0.220UF
J 2
(-6025 3625);
DISPLAY 0.617021 (-6025 3625);
PAINT SKYBLUE (-6025 3625);
FORCEPROP 1 LAST VOLTAGE 16V
J 2
(-6025 3575);
DISPLAY 0.617021 (-6025 3575);
PAINT SKYBLUE (-6025 3575);
FORCEPROP 1 LASTPIN (-5975 3475) $PN 2
J 2
(-5985 3455);
DISPLAY 0.617021 (-5985 3455);
PAINT ORANGE (-5985 3455);
FORCEPROP 1 LAST MATERIAL X7R
J 2
(-6025 3475);
DISPLAY 0.617021 (-6025 3475);
PAINT SKYBLUE (-6025 3475);
FORCEPROP 1 LAST PART_NUMBER A36096-104
J 2
(-6025 3425);
DISPLAY 0.617021 (-6025 3425);
PAINT BLUE (-6025 3425);
FORCEPROP 1 LAST PACK_TYPE 0402
J 2
(-6025 3375);
DISPLAY 0.617021 (-6025 3375);
PAINT SKYBLUE (-6025 3375);
FORCEPROP 1 LAST TOLERANCE 10%
J 2
(-6025 3525);
DISPLAY 0.617021 (-6025 3525);
PAINT SKYBLUE (-6025 3525);
FORCEPROP 2 LAST CDS_LIB mstr_discrete
J 0
(-5975 3575);
PAINT ORANGE (-5975 3575);
DISPLAY INVISIBLE (-5975 3575);
FORCEPROP 2 LAST SEC_TYPE 0402
J 0
(-6025 3775);
DISPLAY 1.021277 (-6025 3775);
PAINT ORANGE (-6025 3775);
DISPLAY INVISIBLE (-6025 3775);
FORCEPROP 0 LAST SPOF TRUE
J 0
(-6025 3775);
DISPLAY 1.021277 (-6025 3775);
PAINT ORANGE (-6025 3775);
DISPLAY INVISIBLE (-6025 3775);
FORCEPROP 2 LAST SEC 1
J 0
(-6025 3775);
DISPLAY 0.680851 (-6025 3775);
PAINT MONO (-6025 3775);
DISPLAY INVISIBLE (-6025 3775);
FORCEPROP 2 LAST CDS_LOCATION C1D20
J 2
(-6025 3675);
DISPLAY 0.617021 (-6025 3675);
PAINT AQUA (-6025 3675);
DISPLAY INVISIBLE (-6025 3675);
FORCEPROP 2 LAST NO_XNET_CONNECTION 1
J 0
(-6025 3775);
PAINT MONO (-6025 3775);
DISPLAY INVISIBLE (-6025 3775);
FORCEPROP 1 LAST PATH I40
J 2
(-6025 3725);
DISPLAY 0.978723 (-6025 3725);
PAINT WHITE (-6025 3725);
DISPLAY INVISIBLE (-6025 3725);
FORCEPROP 2 LAST ROOM PVCCIN_CPU1_PWR_VR
J 0
(-6050 3725);
DISPLAY 1.361702 (-6050 3725);
PAINT ORANGE (-6050 3725);
DISPLAY INVISIBLE (-6050 3725);
FORCEADD CAP..1
(-5500 4150);
FORCEPROP 1 LAST VALUE 1.0UF
J 0
(-5450 4200);
DISPLAY 0.617021 (-5450 4200);
PAINT SKYBLUE (-5450 4200);
FORCEPROP 1 LASTPIN (-5500 4050) $PN 2
J 0
(-5490 4030);
DISPLAY 0.617021 (-5490 4030);
PAINT ORANGE (-5490 4030);
FORCEPROP 1 LASTPIN (-5500 4250) $PN 1
J 0
(-5490 4230);
DISPLAY 0.617021 (-5490 4230);
PAINT ORANGE (-5490 4230);
FORCEPROP 1 LAST VOLTAGE 16V
J 0
(-5450 4150);
DISPLAY 0.617021 (-5450 4150);
PAINT SKYBLUE (-5450 4150);
FORCEPROP 1 LAST TOLERANCE 10%
J 0
(-5450 4100);
DISPLAY 0.617021 (-5450 4100);
PAINT SKYBLUE (-5450 4100);
FORCEPROP 1 LAST MATERIAL X6S
J 0
(-5450 4050);
DISPLAY 0.617021 (-5450 4050);
PAINT SKYBLUE (-5450 4050);
FORCEPROP 1 LAST PACK_TYPE 0402
J 0
(-5450 3950);
DISPLAY 0.617021 (-5450 3950);
PAINT SKYBLUE (-5450 3950);
FORCEPROP 1 LAST PART_NUMBER D97712-011
J 0
(-5450 4000);
DISPLAY 0.617021 (-5450 4000);
PAINT BLUE (-5450 4000);
FORCEPROP 1 LAST LOCATION C1D17
J 0
(-5450 4250);
DISPLAY 0.617021 (-5450 4250);
PAINT AQUA (-5450 4250);
FORCEPROP 1 LAST PATH I43
J 0
(-5450 4300);
DISPLAY 0.978723 (-5450 4300);
PAINT WHITE (-5450 4300);
DISPLAY INVISIBLE (-5450 4300);
FORCEPROP 2 LAST CDS_LOCATION C1D17
J 0
(-5450 4250);
DISPLAY 0.617021 (-5450 4250);
PAINT AQUA (-5450 4250);
DISPLAY INVISIBLE (-5450 4250);
FORCEPROP 2 LAST CDS_LIB mstr_discrete
J 0
(-5500 4150);
PAINT ORANGE (-5500 4150);
DISPLAY INVISIBLE (-5500 4150);
FORCEPROP 2 LAST ROOM PVCCIN_CPU1_PWR_VR
J 0
(-5450 4300);
DISPLAY 1.361702 (-5450 4300);
PAINT ORANGE (-5450 4300);
DISPLAY INVISIBLE (-5450 4300);
FORCEPROP 2 LAST SEC 1
J 0
(-5450 4350);
DISPLAY 0.680851 (-5450 4350);
PAINT MONO (-5450 4350);
DISPLAY INVISIBLE (-5450 4350);
FORCEPROP 2 LAST SEC_TYPE 0402
J 0
(-5450 4350);
DISPLAY 1.021277 (-5450 4350);
PAINT ORANGE (-5450 4350);
DISPLAY INVISIBLE (-5450 4350);
FORCEADD CAP_A..1
(-5775 4150);
FORCEPROP 1 LAST VOLTAGE 16V
J 0
(-5725 4150);
DISPLAY 0.617021 (-5725 4150);
PAINT SKYBLUE (-5725 4150);
FORCEPROP 1 LASTPIN (-5775 4050) $PN 2
J 0
(-5765 4030);
DISPLAY 0.617021 (-5765 4030);
PAINT ORANGE (-5765 4030);
FORCEPROP 1 LASTPIN (-5775 4250) $PN 1
J 0
(-5765 4230);
DISPLAY 0.617021 (-5765 4230);
PAINT ORANGE (-5765 4230);
FORCEPROP 1 LAST LOCATION C1D28
J 0
(-5725 4250);
DISPLAY 0.617021 (-5725 4250);
PAINT AQUA (-5725 4250);
FORCEPROP 1 LAST VALUE 0.1UF
J 0
(-5725 4200);
DISPLAY 0.617021 (-5725 4200);
PAINT SKYBLUE (-5725 4200);
FORCEPROP 1 LAST PACK_TYPE 0402V
J 0
(-5725 3950);
DISPLAY 0.617021 (-5725 3950);
PAINT SKYBLUE (-5725 3950);
FORCEPROP 1 LAST PART_NUMBER A36096-030
J 0
(-5725 4000);
DISPLAY 0.617021 (-5725 4000);
PAINT BLUE (-5725 4000);
FORCEPROP 1 LAST MATERIAL X7R
J 0
(-5725 4050);
DISPLAY 0.617021 (-5725 4050);
PAINT SKYBLUE (-5725 4050);
FORCEPROP 1 LAST TOLERANCE 10%
J 0
(-5725 4100);
DISPLAY 0.617021 (-5725 4100);
PAINT SKYBLUE (-5725 4100);
FORCEPROP 1 LAST PATH I44
J 0
(-5725 4300);
DISPLAY 0.978723 (-5725 4300);
PAINT WHITE (-5725 4300);
DISPLAY INVISIBLE (-5725 4300);
FORCEPROP 2 LAST CDS_LOCATION C1D28
J 0
(-5725 4250);
DISPLAY 0.617021 (-5725 4250);
PAINT AQUA (-5725 4250);
DISPLAY INVISIBLE (-5725 4250);
FORCEPROP 2 LAST CDS_LIB dev_discrete
J 0
(-5775 4150);
PAINT ORANGE (-5775 4150);
DISPLAY INVISIBLE (-5775 4150);
FORCEPROP 2 LAST CDS_SEC 1
J 0
(-5725 4300);
PAINT ORANGE (-5725 4300);
DISPLAY INVISIBLE (-5725 4300);
FORCEPROP 2 LAST ROOM PVCCIN_CPU1_PWR_VR
J 0
(-5725 4300);
DISPLAY 1.361702 (-5725 4300);
PAINT ORANGE (-5725 4300);
DISPLAY INVISIBLE (-5725 4300);
FORCEPROP 2 LAST SEC_TYPE 0402V
J 0
(-5725 4350);
DISPLAY 1.021277 (-5725 4350);
PAINT ORANGE (-5725 4350);
DISPLAY INVISIBLE (-5725 4350);
FORCEPROP 2 LAST SEC 1
J 0
(-5725 4350);
DISPLAY 0.680851 (-5725 4350);
PAINT MONO (-5725 4350);
DISPLAY INVISIBLE (-5725 4350);
FORCEADD CAP..1
(-6025 4150);
FORCEPROP 1 LASTPIN (-6025 4050) $PN 2
J 0
(-6015 4030);
DISPLAY 0.617021 (-6015 4030);
PAINT ORANGE (-6015 4030);
FORCEPROP 1 LAST MATERIAL X6S
J 0
(-5975 4050);
DISPLAY 0.617021 (-5975 4050);
PAINT SKYBLUE (-5975 4050);
FORCEPROP 1 LASTPIN (-6025 4250) $PN 1
J 0
(-6015 4230);
DISPLAY 0.617021 (-6015 4230);
PAINT ORANGE (-6015 4230);
FORCEPROP 1 LAST VOLTAGE 16V
J 0
(-5975 4150);
DISPLAY 0.617021 (-5975 4150);
PAINT SKYBLUE (-5975 4150);
FORCEPROP 1 LAST TOLERANCE 10%
J 0
(-5975 4100);
DISPLAY 0.617021 (-5975 4100);
PAINT SKYBLUE (-5975 4100);
FORCEPROP 1 LAST VALUE 1.0UF
J 0
(-5975 4200);
DISPLAY 0.617021 (-5975 4200);
PAINT SKYBLUE (-5975 4200);
FORCEPROP 1 LAST LOCATION C1D23
J 0
(-5975 4250);
DISPLAY 0.617021 (-5975 4250);
PAINT AQUA (-5975 4250);
FORCEPROP 1 LAST PART_NUMBER D97712-011
J 0
(-5975 4000);
DISPLAY 0.617021 (-5975 4000);
PAINT BLUE (-5975 4000);
FORCEPROP 1 LAST PACK_TYPE 0402
J 0
(-5975 3950);
DISPLAY 0.617021 (-5975 3950);
PAINT SKYBLUE (-5975 3950);
FORCEPROP 2 LAST CDS_LIB mstr_discrete
J 0
(-6025 4150);
PAINT ORANGE (-6025 4150);
DISPLAY INVISIBLE (-6025 4150);
FORCEPROP 2 LAST CDS_LOCATION C1D23
J 0
(-5975 4250);
DISPLAY 0.617021 (-5975 4250);
PAINT AQUA (-5975 4250);
DISPLAY INVISIBLE (-5975 4250);
FORCEPROP 1 LAST PATH I45
J 0
(-5975 4300);
DISPLAY 0.978723 (-5975 4300);
PAINT WHITE (-5975 4300);
DISPLAY INVISIBLE (-5975 4300);
FORCEPROP 2 LAST SEC_TYPE 0402
J 0
(-5975 4350);
DISPLAY 1.021277 (-5975 4350);
PAINT ORANGE (-5975 4350);
DISPLAY INVISIBLE (-5975 4350);
FORCEPROP 2 LAST SEC 1
J 0
(-5975 4350);
DISPLAY 0.680851 (-5975 4350);
PAINT MONO (-5975 4350);
DISPLAY INVISIBLE (-5975 4350);
FORCEPROP 2 LAST ROOM PVCCIN_CPU1_PWR_VR
J 0
(-5975 4300);
DISPLAY 1.361702 (-5975 4300);
PAINT ORANGE (-5975 4300);
DISPLAY INVISIBLE (-5975 4300);
FORCEADD CAP..1
(-4800 1575);
FORCEPROP 1 LASTPIN (-4800 1475) $PN 2
J 0
(-4790 1455);
DISPLAY 0.617021 (-4790 1455);
PAINT ORANGE (-4790 1455);
FORCEPROP 1 LASTPIN (-4800 1675) $PN 1
J 0
(-4790 1655);
DISPLAY 0.617021 (-4790 1655);
PAINT ORANGE (-4790 1655);
FORCEPROP 1 LAST VOLTAGE 16V
J 0
(-4750 1575);
DISPLAY 0.617021 (-4750 1575);
PAINT SKYBLUE (-4750 1575);
FORCEPROP 1 LAST TOLERANCE 10%
J 0
(-4750 1525);
DISPLAY 0.617021 (-4750 1525);
PAINT SKYBLUE (-4750 1525);
FORCEPROP 1 LAST MATERIAL X7R
J 0
(-4750 1475);
DISPLAY 0.617021 (-4750 1475);
PAINT SKYBLUE (-4750 1475);
FORCEPROP 1 LAST PART_NUMBER A36096-155
J 0
(-4750 1425);
DISPLAY 0.617021 (-4750 1425);
PAINT BLUE (-4750 1425);
FORCEPROP 1 LAST PACK_TYPE 0402
J 0
(-4750 1375);
DISPLAY 0.617021 (-4750 1375);
PAINT SKYBLUE (-4750 1375);
FORCEPROP 1 LAST VALUE 0.22UF
J 0
(-4750 1625);
DISPLAY 0.617021 (-4750 1625);
PAINT SKYBLUE (-4750 1625);
FORCEPROP 1 LAST LOCATION C1D6
J 0
(-4750 1675);
DISPLAY 0.617021 (-4750 1675);
PAINT AQUA (-4750 1675);
FORCEPROP 2 LAST CDS_LIB mstr_discrete
J 0
(-4800 1575);
PAINT ORANGE (-4800 1575);
DISPLAY INVISIBLE (-4800 1575);
FORCEPROP 2 LAST ROOM PVCCIN_CPU1_PWR_VR
J 0
(-4750 1725);
DISPLAY 1.361702 (-4750 1725);
PAINT ORANGE (-4750 1725);
DISPLAY INVISIBLE (-4750 1725);
FORCEPROP 1 LAST PATH I46
J 0
(-4750 1725);
DISPLAY 0.978723 (-4750 1725);
PAINT WHITE (-4750 1725);
DISPLAY INVISIBLE (-4750 1725);
FORCEPROP 2 LAST CDS_LOCATION C1D6
J 0
(-4750 1675);
DISPLAY 0.617021 (-4750 1675);
PAINT AQUA (-4750 1675);
DISPLAY INVISIBLE (-4750 1675);
FORCEPROP 2 LAST SEC 1
J 0
(-4750 1775);
DISPLAY 0.680851 (-4750 1775);
PAINT MONO (-4750 1775);
DISPLAY INVISIBLE (-4750 1775);
FORCEPROP 2 LAST SEC_TYPE 0402
J 0
(-4750 1775);
DISPLAY 1.021277 (-4750 1775);
PAINT ORANGE (-4750 1775);
DISPLAY INVISIBLE (-4750 1775);
FORCEADD CAP..1
R 2
(-5975 900);
FORCEPROP 1 LAST PACK_TYPE 0402
J 2
(-6025 700);
DISPLAY 0.617021 (-6025 700);
PAINT SKYBLUE (-6025 700);
FORCEPROP 1 LAST PART_NUMBER A36096-104
J 2
(-6025 750);
DISPLAY 0.617021 (-6025 750);
PAINT BLUE (-6025 750);
FORCEPROP 1 LAST VALUE 0.220UF
J 2
(-6025 950);
DISPLAY 0.617021 (-6025 950);
PAINT SKYBLUE (-6025 950);
FORCEPROP 1 LAST TOLERANCE 10%
J 2
(-6025 850);
DISPLAY 0.617021 (-6025 850);
PAINT SKYBLUE (-6025 850);
FORCEPROP 1 LAST MATERIAL X7R
J 2
(-6025 800);
DISPLAY 0.617021 (-6025 800);
PAINT SKYBLUE (-6025 800);
FORCEPROP 1 LASTPIN (-5975 800) $PN 2
J 2
(-5985 780);
DISPLAY 0.617021 (-5985 780);
PAINT ORANGE (-5985 780);
FORCEPROP 1 LAST VOLTAGE 16V
J 2
(-6025 900);
DISPLAY 0.617021 (-6025 900);
PAINT SKYBLUE (-6025 900);
FORCEPROP 1 LAST LOCATION C1D10
J 2
(-6025 1000);
DISPLAY 0.617021 (-6025 1000);
PAINT AQUA (-6025 1000);
FORCEPROP 1 LASTPIN (-5975 1000) $PN 1
J 2
(-5985 980);
DISPLAY 0.617021 (-5985 980);
PAINT ORANGE (-5985 980);
FORCEPROP 0 LAST SPOF TRUE
J 0
(-6025 1100);
DISPLAY 1.021277 (-6025 1100);
PAINT ORANGE (-6025 1100);
DISPLAY INVISIBLE (-6025 1100);
FORCEPROP 2 LAST SEC_TYPE 0402
J 0
(-6025 1100);
DISPLAY 1.021277 (-6025 1100);
PAINT ORANGE (-6025 1100);
DISPLAY INVISIBLE (-6025 1100);
FORCEPROP 2 LAST SEC 1
J 0
(-6025 1100);
DISPLAY 0.680851 (-6025 1100);
PAINT MONO (-6025 1100);
DISPLAY INVISIBLE (-6025 1100);
FORCEPROP 2 LAST CDS_LOCATION C1D10
J 2
(-6025 1000);
DISPLAY 0.617021 (-6025 1000);
PAINT AQUA (-6025 1000);
DISPLAY INVISIBLE (-6025 1000);
FORCEPROP 2 LAST NO_XNET_CONNECTION 1
J 0
(-6025 1100);
PAINT MONO (-6025 1100);
DISPLAY INVISIBLE (-6025 1100);
FORCEPROP 1 LAST PATH I48
J 2
(-6025 1050);
DISPLAY 0.978723 (-6025 1050);
PAINT WHITE (-6025 1050);
DISPLAY INVISIBLE (-6025 1050);
FORCEPROP 2 LAST ROOM PVCCIN_CPU1_PWR_VR
J 0
(-6025 1050);
DISPLAY 1.361702 (-6025 1050);
PAINT ORANGE (-6025 1050);
DISPLAY INVISIBLE (-6025 1050);
FORCEPROP 2 LAST CDS_LIB mstr_discrete
J 0
(-5975 900);
PAINT ORANGE (-5975 900);
DISPLAY INVISIBLE (-5975 900);
FORCEADD CAP..1
(-5700 1575);
FORCEPROP 1 LAST PACK_TYPE 0402
J 0
(-5650 1375);
DISPLAY 0.617021 (-5650 1375);
PAINT SKYBLUE (-5650 1375);
FORCEPROP 1 LASTPIN (-5700 1475) $PN 2
J 0
(-5690 1455);
DISPLAY 0.617021 (-5690 1455);
PAINT ORANGE (-5690 1455);
FORCEPROP 1 LASTPIN (-5700 1675) $PN 1
J 0
(-5690 1655);
DISPLAY 0.617021 (-5690 1655);
PAINT ORANGE (-5690 1655);
FORCEPROP 1 LAST MATERIAL X6S
J 0
(-5650 1475);
DISPLAY 0.617021 (-5650 1475);
PAINT SKYBLUE (-5650 1475);
FORCEPROP 1 LAST TOLERANCE 10%
J 0
(-5650 1525);
DISPLAY 0.617021 (-5650 1525);
PAINT SKYBLUE (-5650 1525);
FORCEPROP 1 LAST VOLTAGE 16V
J 0
(-5650 1575);
DISPLAY 0.617021 (-5650 1575);
PAINT SKYBLUE (-5650 1575);
FORCEPROP 1 LAST PART_NUMBER D97712-011
J 0
(-5650 1425);
DISPLAY 0.617021 (-5650 1425);
PAINT BLUE (-5650 1425);
FORCEPROP 1 LAST VALUE 1.0UF
J 0
(-5650 1625);
DISPLAY 0.617021 (-5650 1625);
PAINT SKYBLUE (-5650 1625);
FORCEPROP 1 LAST LOCATION C1D7
J 0
(-5650 1675);
DISPLAY 0.617021 (-5650 1675);
PAINT AQUA (-5650 1675);
FORCEPROP 2 LAST CDS_LIB mstr_discrete
J 0
(-5700 1575);
PAINT ORANGE (-5700 1575);
DISPLAY INVISIBLE (-5700 1575);
FORCEPROP 2 LAST CDS_LOCATION C1D7
J 0
(-5650 1675);
DISPLAY 0.617021 (-5650 1675);
PAINT AQUA (-5650 1675);
DISPLAY INVISIBLE (-5650 1675);
FORCEPROP 1 LAST PATH I50
J 0
(-5650 1725);
DISPLAY 0.978723 (-5650 1725);
PAINT WHITE (-5650 1725);
DISPLAY INVISIBLE (-5650 1725);
FORCEPROP 2 LAST ROOM PVCCIN_CPU1_PWR_VR
J 0
(-5650 1725);
DISPLAY 1.361702 (-5650 1725);
PAINT ORANGE (-5650 1725);
DISPLAY INVISIBLE (-5650 1725);
FORCEPROP 2 LAST SEC_TYPE 0402
J 0
(-5650 1775);
DISPLAY 1.021277 (-5650 1775);
PAINT ORANGE (-5650 1775);
DISPLAY INVISIBLE (-5650 1775);
FORCEPROP 2 LAST SEC 1
J 0
(-5650 1775);
DISPLAY 0.680851 (-5650 1775);
PAINT MONO (-5650 1775);
DISPLAY INVISIBLE (-5650 1775);
FORCEADD CAP_A..1
(-5950 1575);
FORCEPROP 1 LASTPIN (-5950 1675) $PN 1
J 0
(-5940 1655);
DISPLAY 0.617021 (-5940 1655);
PAINT ORANGE (-5940 1655);
FORCEPROP 1 LAST VOLTAGE 16V
J 0
(-5900 1575);
DISPLAY 0.617021 (-5900 1575);
PAINT SKYBLUE (-5900 1575);
FORCEPROP 1 LAST PACK_TYPE 0402V
J 0
(-5900 1375);
DISPLAY 0.617021 (-5900 1375);
PAINT SKYBLUE (-5900 1375);
FORCEPROP 1 LAST TOLERANCE 10%
J 0
(-5900 1525);
DISPLAY 0.617021 (-5900 1525);
PAINT SKYBLUE (-5900 1525);
FORCEPROP 1 LASTPIN (-5950 1475) $PN 2
J 0
(-5940 1455);
DISPLAY 0.617021 (-5940 1455);
PAINT ORANGE (-5940 1455);
FORCEPROP 1 LAST MATERIAL X7R
J 0
(-5900 1475);
DISPLAY 0.617021 (-5900 1475);
PAINT SKYBLUE (-5900 1475);
FORCEPROP 1 LAST PART_NUMBER A36096-030
J 0
(-5900 1425);
DISPLAY 0.617021 (-5900 1425);
PAINT BLUE (-5900 1425);
FORCEPROP 1 LAST VALUE 0.1UF
J 0
(-5900 1625);
DISPLAY 0.617021 (-5900 1625);
PAINT SKYBLUE (-5900 1625);
FORCEPROP 1 LAST LOCATION C1D13
J 0
(-5900 1675);
DISPLAY 0.617021 (-5900 1675);
PAINT AQUA (-5900 1675);
FORCEPROP 2 LAST SEC 1
J 0
(-5900 1775);
DISPLAY 0.680851 (-5900 1775);
PAINT MONO (-5900 1775);
DISPLAY INVISIBLE (-5900 1775);
FORCEPROP 2 LAST SEC_TYPE 0402V
J 0
(-5900 1775);
DISPLAY 1.021277 (-5900 1775);
PAINT ORANGE (-5900 1775);
DISPLAY INVISIBLE (-5900 1775);
FORCEPROP 2 LAST CDS_SEC 1
J 0
(-5900 1725);
PAINT ORANGE (-5900 1725);
DISPLAY INVISIBLE (-5900 1725);
FORCEPROP 2 LAST CDS_LOCATION C1D13
J 0
(-5900 1675);
DISPLAY 0.617021 (-5900 1675);
PAINT AQUA (-5900 1675);
DISPLAY INVISIBLE (-5900 1675);
FORCEPROP 2 LAST ROOM PVCCIN_CPU1_PWR_VR
J 0
(-5900 1725);
DISPLAY 1.361702 (-5900 1725);
PAINT ORANGE (-5900 1725);
DISPLAY INVISIBLE (-5900 1725);
FORCEPROP 1 LAST PATH I51
J 0
(-5900 1725);
DISPLAY 0.978723 (-5900 1725);
PAINT WHITE (-5900 1725);
DISPLAY INVISIBLE (-5900 1725);
FORCEPROP 2 LAST CDS_LIB dev_discrete
J 0
(-5950 1575);
PAINT ORANGE (-5950 1575);
DISPLAY INVISIBLE (-5950 1575);
FORCEADD CAP..1
(-6250 1575);
FORCEPROP 1 LAST LOCATION C1D12
J 0
(-6200 1675);
DISPLAY 0.617021 (-6200 1675);
PAINT AQUA (-6200 1675);
FORCEPROP 1 LAST VALUE 1.0UF
J 0
(-6200 1625);
DISPLAY 0.617021 (-6200 1625);
PAINT SKYBLUE (-6200 1625);
FORCEPROP 1 LASTPIN (-6250 1675) $PN 1
J 0
(-6240 1655);
DISPLAY 0.617021 (-6240 1655);
PAINT ORANGE (-6240 1655);
FORCEPROP 1 LAST PACK_TYPE 0402
J 0
(-6200 1375);
DISPLAY 0.617021 (-6200 1375);
PAINT SKYBLUE (-6200 1375);
FORCEPROP 1 LAST VOLTAGE 16V
J 0
(-6200 1575);
DISPLAY 0.617021 (-6200 1575);
PAINT SKYBLUE (-6200 1575);
FORCEPROP 1 LAST MATERIAL X6S
J 0
(-6200 1475);
DISPLAY 0.617021 (-6200 1475);
PAINT SKYBLUE (-6200 1475);
FORCEPROP 1 LASTPIN (-6250 1475) $PN 2
J 0
(-6240 1455);
DISPLAY 0.617021 (-6240 1455);
PAINT ORANGE (-6240 1455);
FORCEPROP 1 LAST TOLERANCE 10%
J 0
(-6200 1525);
DISPLAY 0.617021 (-6200 1525);
PAINT SKYBLUE (-6200 1525);
FORCEPROP 1 LAST PART_NUMBER D97712-011
J 0
(-6200 1425);
DISPLAY 0.617021 (-6200 1425);
PAINT BLUE (-6200 1425);
FORCEPROP 2 LAST SEC_TYPE 0402
J 0
(-6200 1775);
DISPLAY 1.021277 (-6200 1775);
PAINT ORANGE (-6200 1775);
DISPLAY INVISIBLE (-6200 1775);
FORCEPROP 2 LAST SEC 1
J 0
(-6200 1775);
DISPLAY 0.680851 (-6200 1775);
PAINT MONO (-6200 1775);
DISPLAY INVISIBLE (-6200 1775);
FORCEPROP 2 LAST CDS_LOCATION C1D12
J 0
(-6200 1675);
DISPLAY 0.617021 (-6200 1675);
PAINT AQUA (-6200 1675);
DISPLAY INVISIBLE (-6200 1675);
FORCEPROP 1 LAST PATH I52
J 0
(-6200 1725);
DISPLAY 0.978723 (-6200 1725);
PAINT WHITE (-6200 1725);
DISPLAY INVISIBLE (-6200 1725);
FORCEPROP 2 LAST ROOM PVCCIN_CPU1_PWR_VR
J 0
(-6200 1725);
DISPLAY 1.361702 (-6200 1725);
PAINT ORANGE (-6200 1725);
DISPLAY INVISIBLE (-6200 1725);
FORCEPROP 2 LAST CDS_LIB mstr_discrete
J 0
(-6250 1575);
PAINT ORANGE (-6250 1575);
DISPLAY INVISIBLE (-6250 1575);
FORCEADD CAP..1
(-6275 4150);
FORCEPROP 1 LASTPIN (-6275 4050) $PN 2
J 0
(-6265 4030);
DISPLAY 0.617021 (-6265 4030);
PAINT ORANGE (-6265 4030);
FORCEPROP 1 LAST MATERIAL X6S
J 0
(-6225 4050);
DISPLAY 0.617021 (-6225 4050);
PAINT SKYBLUE (-6225 4050);
FORCEPROP 1 LAST PART_NUMBER C95333-007
J 0
(-6225 4000);
DISPLAY 0.617021 (-6225 4000);
PAINT BLUE (-6225 4000);
FORCEPROP 1 LAST LOCATION C9P4
J 0
(-6225 4250);
DISPLAY 0.617021 (-6225 4250);
PAINT AQUA (-6225 4250);
FORCEPROP 1 LAST VALUE 10UF
J 0
(-6225 4200);
DISPLAY 0.617021 (-6225 4200);
PAINT SKYBLUE (-6225 4200);
FORCEPROP 1 LAST TOLERANCE 10%
J 0
(-6225 4100);
DISPLAY 0.617021 (-6225 4100);
PAINT SKYBLUE (-6225 4100);
FORCEPROP 1 LAST VOLTAGE 16V
J 0
(-6225 4150);
DISPLAY 0.617021 (-6225 4150);
PAINT SKYBLUE (-6225 4150);
FORCEPROP 1 LASTPIN (-6275 4250) $PN 1
J 0
(-6265 4230);
DISPLAY 0.617021 (-6265 4230);
PAINT ORANGE (-6265 4230);
FORCEPROP 1 LAST PACK_TYPE 0805
J 0
(-6225 3950);
DISPLAY 0.617021 (-6225 3950);
PAINT SKYBLUE (-6225 3950);
FORCEPROP 2 LAST CDS_LIB mstr_discrete
J 0
(-6275 4150);
PAINT ORANGE (-6275 4150);
DISPLAY INVISIBLE (-6275 4150);
FORCEPROP 2 LAST CDS_LOCATION C9P4
J 0
(-6225 4250);
DISPLAY 0.617021 (-6225 4250);
PAINT AQUA (-6225 4250);
DISPLAY INVISIBLE (-6225 4250);
FORCEPROP 1 LAST PATH I53
J 0
(-6225 4300);
DISPLAY 0.978723 (-6225 4300);
PAINT WHITE (-6225 4300);
DISPLAY INVISIBLE (-6225 4300);
FORCEPROP 2 LAST SEC_TYPE 0805
J 0
(-6225 4350);
DISPLAY 1.021277 (-6225 4350);
PAINT ORANGE (-6225 4350);
DISPLAY INVISIBLE (-6225 4350);
FORCEPROP 2 LAST SEC 1
J 0
(-6225 4350);
DISPLAY 0.680851 (-6225 4350);
PAINT MONO (-6225 4350);
DISPLAY INVISIBLE (-6225 4350);
FORCEPROP 2 LAST ROOM PVCCIN_CPU1_PWR_VR
J 0
(-6225 4300);
DISPLAY 1.361702 (-6225 4300);
PAINT ORANGE (-6225 4300);
DISPLAY INVISIBLE (-6225 4300);
FORCEADD CAP..1
(-6550 4150);
FORCEPROP 1 LASTPIN (-6550 4050) $PN 2
J 0
(-6540 4030);
DISPLAY 0.617021 (-6540 4030);
PAINT ORANGE (-6540 4030);
FORCEPROP 1 LAST MATERIAL X6S
J 0
(-6500 4050);
DISPLAY 0.617021 (-6500 4050);
PAINT SKYBLUE (-6500 4050);
FORCEPROP 1 LAST PACK_TYPE 0805
J 0
(-6500 3950);
DISPLAY 0.617021 (-6500 3950);
PAINT SKYBLUE (-6500 3950);
FORCEPROP 1 LASTPIN (-6550 4250) $PN 1
J 0
(-6540 4230);
DISPLAY 0.617021 (-6540 4230);
PAINT ORANGE (-6540 4230);
FORCEPROP 1 LAST VOLTAGE 16V
J 0
(-6500 4150);
DISPLAY 0.617021 (-6500 4150);
PAINT SKYBLUE (-6500 4150);
FORCEPROP 1 LAST TOLERANCE 10%
J 0
(-6500 4100);
DISPLAY 0.617021 (-6500 4100);
PAINT SKYBLUE (-6500 4100);
FORCEPROP 1 LAST VALUE 10UF
J 0
(-6500 4200);
DISPLAY 0.617021 (-6500 4200);
PAINT SKYBLUE (-6500 4200);
FORCEPROP 1 LAST LOCATION C9P7
J 0
(-6500 4250);
DISPLAY 0.617021 (-6500 4250);
PAINT AQUA (-6500 4250);
FORCEPROP 1 LAST PART_NUMBER C95333-007
J 0
(-6500 4000);
DISPLAY 0.617021 (-6500 4000);
PAINT BLUE (-6500 4000);
FORCEPROP 2 LAST CDS_LIB mstr_discrete
J 0
(-6550 4150);
PAINT ORANGE (-6550 4150);
DISPLAY INVISIBLE (-6550 4150);
FORCEPROP 2 LAST CDS_LOCATION C9P7
J 0
(-6500 4250);
DISPLAY 0.617021 (-6500 4250);
PAINT AQUA (-6500 4250);
DISPLAY INVISIBLE (-6500 4250);
FORCEPROP 1 LAST PATH I54
J 0
(-6500 4300);
DISPLAY 0.978723 (-6500 4300);
PAINT WHITE (-6500 4300);
DISPLAY INVISIBLE (-6500 4300);
FORCEPROP 2 LAST SEC_TYPE 0805
J 0
(-6500 4350);
DISPLAY 1.021277 (-6500 4350);
PAINT ORANGE (-6500 4350);
DISPLAY INVISIBLE (-6500 4350);
FORCEPROP 2 LAST SEC 1
J 0
(-6500 4350);
DISPLAY 0.680851 (-6500 4350);
PAINT MONO (-6500 4350);
DISPLAY INVISIBLE (-6500 4350);
FORCEPROP 2 LAST ROOM PVCCIN_CPU1_PWR_VR
J 0
(-6500 4300);
DISPLAY 1.361702 (-6500 4300);
PAINT ORANGE (-6500 4300);
DISPLAY INVISIBLE (-6500 4300);
FORCEADD CAP..1
(-6875 4150);
FORCEPROP 1 LAST PART_NUMBER C95333-007
J 0
(-6825 4000);
DISPLAY 0.617021 (-6825 4000);
PAINT BLUE (-6825 4000);
FORCEPROP 1 LAST PACK_TYPE 0805
J 0
(-6825 3950);
DISPLAY 0.617021 (-6825 3950);
PAINT SKYBLUE (-6825 3950);
FORCEPROP 1 LAST MATERIAL X6S
J 0
(-6825 4050);
DISPLAY 0.617021 (-6825 4050);
PAINT SKYBLUE (-6825 4050);
FORCEPROP 1 LASTPIN (-6875 4050) $PN 2
J 0
(-6865 4030);
DISPLAY 0.617021 (-6865 4030);
PAINT ORANGE (-6865 4030);
FORCEPROP 1 LASTPIN (-6875 4250) $PN 1
J 0
(-6865 4230);
DISPLAY 0.617021 (-6865 4230);
PAINT ORANGE (-6865 4230);
FORCEPROP 1 LAST VALUE 10UF
J 0
(-6825 4200);
DISPLAY 0.617021 (-6825 4200);
PAINT SKYBLUE (-6825 4200);
FORCEPROP 1 LAST LOCATION C9P9
J 0
(-6825 4250);
DISPLAY 0.617021 (-6825 4250);
PAINT AQUA (-6825 4250);
FORCEPROP 1 LAST VOLTAGE 16V
J 0
(-6825 4150);
DISPLAY 0.617021 (-6825 4150);
PAINT SKYBLUE (-6825 4150);
FORCEPROP 1 LAST TOLERANCE 10%
J 0
(-6825 4100);
DISPLAY 0.617021 (-6825 4100);
PAINT SKYBLUE (-6825 4100);
FORCEPROP 2 LAST CDS_LIB mstr_discrete
J 0
(-6875 4150);
PAINT ORANGE (-6875 4150);
DISPLAY INVISIBLE (-6875 4150);
FORCEPROP 2 LAST CDS_LOCATION C9P9
J 0
(-6825 4250);
DISPLAY 0.617021 (-6825 4250);
PAINT AQUA (-6825 4250);
DISPLAY INVISIBLE (-6825 4250);
FORCEPROP 1 LAST PATH I55
J 0
(-6825 4300);
DISPLAY 0.978723 (-6825 4300);
PAINT WHITE (-6825 4300);
DISPLAY INVISIBLE (-6825 4300);
FORCEPROP 2 LAST ROOM PVCCIN_CPU1_PWR_VR
J 0
(-6825 4300);
DISPLAY 1.361702 (-6825 4300);
PAINT ORANGE (-6825 4300);
DISPLAY INVISIBLE (-6825 4300);
FORCEPROP 2 LAST SEC 1
J 0
(-6825 4350);
DISPLAY 0.680851 (-6825 4350);
PAINT MONO (-6825 4350);
DISPLAY INVISIBLE (-6825 4350);
FORCEPROP 2 LAST SEC_TYPE 0805
J 0
(-6825 4350);
DISPLAY 1.021277 (-6825 4350);
PAINT ORANGE (-6825 4350);
DISPLAY INVISIBLE (-6825 4350);
FORCEADD OFFPAGE..1
(-6550 3775);
FORCEPROP 2 LASTPIN (-6500 3775) SIG_NAME VR_PVCCIN_CPU1_PWM3
J 0
(-6485 3785);
DISPLAY 0.617021 (-6485 3785);
PAINT ORANGE (-6485 3785);
FORCEPROP 2 LAST $XR0 206 
J 0
(-6802 3775);
DISPLAY 0.638298 (-6802 3775);
PAINT MONO (-6802 3775);
FORCEPROP 1 LAST COMMENT_BODY TRUE
J 0
(-6425 3675);
DISPLAY 1.680851 (-6425 3675);
PAINT GREEN (-6425 3675);
DISPLAY INVISIBLE (-6425 3675);
FORCEPROP 1 LAST OFFPAGE TRUE
J 0
(-6225 3650);
DISPLAY 1.680851 (-6225 3650);
PAINT GREEN (-6225 3650);
DISPLAY INVISIBLE (-6225 3650);
FORCEPROP 2 LAST ROOM PVCCIN_CPU1_PWR_VR
J 0
(-6950 3850);
DISPLAY 1.936170 (-6950 3850);
PAINT ORANGE (-6950 3850);
DISPLAY INVISIBLE (-6950 3850);
FORCEPROP 2 LAST BOM_COST PROC_VRD_VCCIN_CPU0
J 0
(-6800 3825);
DISPLAY 1.446809 (-6800 3825);
PAINT MONO (-6800 3825);
DISPLAY INVISIBLE (-6800 3825);
FORCEPROP 2 LAST PATH I56
J 0
(-6795 3825);
DISPLAY 1.021277 (-6795 3825);
PAINT ORANGE (-6795 3825);
DISPLAY INVISIBLE (-6795 3825);
FORCEPROP 2 LAST CDS_LIB mstr_standard
J 0
(-6550 3775);
DISPLAY 1.936170 (-6550 3775);
PAINT ORANGE (-6550 3775);
DISPLAY INVISIBLE (-6550 3775);
FORCEADD GND..1
(-6875 3650);
FORCEPROP 3 LASTPIN (-6875 3700) SIG_NAME GND\g
J 0
(-6865 3710);
DISPLAY 0.659574 (-6865 3710);
PAINT MONO (-6865 3710);
DISPLAY INVISIBLE (-6865 3710);
FORCEPROP 1 LAST HDL_POWER GND
J 0
(-6875 3800);
DISPLAY 1.723404 (-6875 3800);
PAINT GREEN (-6875 3800);
DISPLAY INVISIBLE (-6875 3800);
FORCEPROP 1 LAST BODY_TYPE PLUMBING
J 0
(-6920 3607);
DISPLAY 0.340426 (-6920 3607);
PAINT GREEN (-6920 3607);
DISPLAY INVISIBLE (-6920 3607);
FORCEPROP 2 LAST ROOM PVCCIN_CPU1_PWR_VR
J 0
(-7425 3725);
DISPLAY 1.936170 (-7425 3725);
PAINT ORANGE (-7425 3725);
DISPLAY INVISIBLE (-7425 3725);
FORCEPROP 2 LAST BOM_COST PROC_VRD_VCCIN_CPU0
J 0
(-7250 3725);
DISPLAY 1.446809 (-7250 3725);
PAINT MONO (-7250 3725);
DISPLAY INVISIBLE (-7250 3725);
FORCEPROP 1 LAST VOLTAGE 0
J 0
(-6875 3650);
PAINT SKYBLUE (-6875 3650);
DISPLAY INVISIBLE (-6875 3650);
FORCEPROP 2 LAST CDS_LIB mstr_symbols
J 0
(-6875 3650);
DISPLAY 1.936170 (-6875 3650);
PAINT ORANGE (-6875 3650);
DISPLAY INVISIBLE (-6875 3650);
FORCEPROP 1 LAST SIZE 1B
J 0
(-6800 3600);
DISPLAY 1.723404 (-6800 3600);
PAINT GREEN (-6800 3600);
DISPLAY INVISIBLE (-6800 3600);
FORCEPROP 1 LAST PATH I57
J 0
(-6800 3650);
DISPLAY 0.872340 (-6800 3650);
PAINT AQUA (-6800 3650);
DISPLAY INVISIBLE (-6800 3650);
FORCEADD CAP..1
(-6500 1575);
FORCEPROP 1 LAST PACK_TYPE 0805
J 0
(-6450 1375);
DISPLAY 0.617021 (-6450 1375);
PAINT SKYBLUE (-6450 1375);
FORCEPROP 1 LASTPIN (-6500 1475) $PN 2
J 0
(-6490 1455);
DISPLAY 0.617021 (-6490 1455);
PAINT ORANGE (-6490 1455);
FORCEPROP 1 LASTPIN (-6500 1675) $PN 1
J 0
(-6490 1655);
DISPLAY 0.617021 (-6490 1655);
PAINT ORANGE (-6490 1655);
FORCEPROP 1 LAST VOLTAGE 16V
J 0
(-6450 1575);
DISPLAY 0.617021 (-6450 1575);
PAINT SKYBLUE (-6450 1575);
FORCEPROP 1 LAST TOLERANCE 10%
J 0
(-6450 1525);
DISPLAY 0.617021 (-6450 1525);
PAINT SKYBLUE (-6450 1525);
FORCEPROP 1 LAST VALUE 10UF
J 0
(-6450 1625);
DISPLAY 0.617021 (-6450 1625);
PAINT SKYBLUE (-6450 1625);
FORCEPROP 1 LAST LOCATION C9P24
J 0
(-6450 1675);
DISPLAY 0.617021 (-6450 1675);
PAINT AQUA (-6450 1675);
FORCEPROP 1 LAST MATERIAL X6S
J 0
(-6450 1475);
DISPLAY 0.617021 (-6450 1475);
PAINT SKYBLUE (-6450 1475);
FORCEPROP 1 LAST PART_NUMBER C95333-007
J 0
(-6450 1425);
DISPLAY 0.617021 (-6450 1425);
PAINT BLUE (-6450 1425);
FORCEPROP 2 LAST CDS_LIB mstr_discrete
J 0
(-6500 1575);
PAINT ORANGE (-6500 1575);
DISPLAY INVISIBLE (-6500 1575);
FORCEPROP 2 LAST SEC_TYPE 0805
J 0
(-6450 1775);
DISPLAY 1.021277 (-6450 1775);
PAINT ORANGE (-6450 1775);
DISPLAY INVISIBLE (-6450 1775);
FORCEPROP 2 LAST SEC 1
J 0
(-6450 1775);
DISPLAY 0.680851 (-6450 1775);
PAINT MONO (-6450 1775);
DISPLAY INVISIBLE (-6450 1775);
FORCEPROP 1 LAST PATH I58
J 0
(-6450 1725);
DISPLAY 0.978723 (-6450 1725);
PAINT WHITE (-6450 1725);
DISPLAY INVISIBLE (-6450 1725);
FORCEPROP 2 LAST ROOM PVCCIN_CPU1_PWR_VR
J 0
(-6450 1725);
DISPLAY 1.361702 (-6450 1725);
PAINT ORANGE (-6450 1725);
DISPLAY INVISIBLE (-6450 1725);
FORCEADD CAP..1
(-6800 1575);
FORCEPROP 1 LAST LOCATION C9P1
J 0
(-6750 1675);
DISPLAY 0.617021 (-6750 1675);
PAINT AQUA (-6750 1675);
FORCEPROP 1 LAST VALUE 10UF
J 0
(-6750 1625);
DISPLAY 0.617021 (-6750 1625);
PAINT SKYBLUE (-6750 1625);
FORCEPROP 1 LAST VOLTAGE 16V
J 0
(-6750 1575);
DISPLAY 0.617021 (-6750 1575);
PAINT SKYBLUE (-6750 1575);
FORCEPROP 1 LAST TOLERANCE 10%
J 0
(-6750 1525);
DISPLAY 0.617021 (-6750 1525);
PAINT SKYBLUE (-6750 1525);
FORCEPROP 1 LAST PART_NUMBER C95333-007
J 0
(-6750 1425);
DISPLAY 0.617021 (-6750 1425);
PAINT BLUE (-6750 1425);
FORCEPROP 1 LAST PACK_TYPE 0805
J 0
(-6750 1375);
DISPLAY 0.617021 (-6750 1375);
PAINT SKYBLUE (-6750 1375);
FORCEPROP 1 LASTPIN (-6800 1675) $PN 1
J 0
(-6790 1655);
DISPLAY 0.617021 (-6790 1655);
PAINT ORANGE (-6790 1655);
FORCEPROP 1 LASTPIN (-6800 1475) $PN 2
J 0
(-6790 1455);
DISPLAY 0.617021 (-6790 1455);
PAINT ORANGE (-6790 1455);
FORCEPROP 1 LAST MATERIAL X6S
J 0
(-6750 1475);
DISPLAY 0.617021 (-6750 1475);
PAINT SKYBLUE (-6750 1475);
FORCEPROP 2 LAST ROOM PVCCIN_CPU1_PWR_VR
J 0
(-6750 1725);
DISPLAY 1.361702 (-6750 1725);
PAINT ORANGE (-6750 1725);
DISPLAY INVISIBLE (-6750 1725);
FORCEPROP 1 LAST PATH I59
J 0
(-6750 1725);
DISPLAY 0.978723 (-6750 1725);
PAINT WHITE (-6750 1725);
DISPLAY INVISIBLE (-6750 1725);
FORCEPROP 2 LAST CDS_LOCATION C9P1
J 0
(-6750 1675);
DISPLAY 0.617021 (-6750 1675);
PAINT AQUA (-6750 1675);
DISPLAY INVISIBLE (-6750 1675);
FORCEPROP 2 LAST SEC 1
J 0
(-6750 1775);
DISPLAY 0.680851 (-6750 1775);
PAINT MONO (-6750 1775);
DISPLAY INVISIBLE (-6750 1775);
FORCEPROP 2 LAST SEC_TYPE 0805
J 0
(-6750 1775);
DISPLAY 1.021277 (-6750 1775);
PAINT ORANGE (-6750 1775);
DISPLAY INVISIBLE (-6750 1775);
FORCEPROP 2 LAST CDS_LIB mstr_discrete
J 0
(-6800 1575);
PAINT ORANGE (-6800 1575);
DISPLAY INVISIBLE (-6800 1575);
FORCEADD CAP..1
(-7050 1575);
FORCEPROP 1 LAST PART_NUMBER C95333-007
J 0
(-7000 1425);
DISPLAY 0.617021 (-7000 1425);
PAINT BLUE (-7000 1425);
FORCEPROP 1 LAST VALUE 10UF
J 0
(-7000 1625);
DISPLAY 0.617021 (-7000 1625);
PAINT SKYBLUE (-7000 1625);
FORCEPROP 1 LAST MATERIAL X6S
J 0
(-7000 1475);
DISPLAY 0.617021 (-7000 1475);
PAINT SKYBLUE (-7000 1475);
FORCEPROP 1 LAST VOLTAGE 16V
J 0
(-7000 1575);
DISPLAY 0.617021 (-7000 1575);
PAINT SKYBLUE (-7000 1575);
FORCEPROP 1 LAST TOLERANCE 10%
J 0
(-7000 1525);
DISPLAY 0.617021 (-7000 1525);
PAINT SKYBLUE (-7000 1525);
FORCEPROP 1 LASTPIN (-7050 1675) $PN 1
J 0
(-7040 1655);
DISPLAY 0.617021 (-7040 1655);
PAINT ORANGE (-7040 1655);
FORCEPROP 1 LAST LOCATION C9P2
J 0
(-7000 1675);
DISPLAY 0.617021 (-7000 1675);
PAINT AQUA (-7000 1675);
FORCEPROP 1 LASTPIN (-7050 1475) $PN 2
J 0
(-7040 1455);
DISPLAY 0.617021 (-7040 1455);
PAINT ORANGE (-7040 1455);
FORCEPROP 1 LAST PACK_TYPE 0805
J 0
(-7000 1375);
DISPLAY 0.617021 (-7000 1375);
PAINT SKYBLUE (-7000 1375);
FORCEPROP 2 LAST CDS_LIB mstr_discrete
J 0
(-7050 1575);
PAINT ORANGE (-7050 1575);
DISPLAY INVISIBLE (-7050 1575);
FORCEPROP 2 LAST SEC_TYPE 0805
J 0
(-7000 1775);
DISPLAY 1.021277 (-7000 1775);
PAINT ORANGE (-7000 1775);
DISPLAY INVISIBLE (-7000 1775);
FORCEPROP 2 LAST SEC 1
J 0
(-7000 1775);
DISPLAY 0.680851 (-7000 1775);
PAINT MONO (-7000 1775);
DISPLAY INVISIBLE (-7000 1775);
FORCEPROP 1 LAST PATH I60
J 0
(-7000 1725);
DISPLAY 0.978723 (-7000 1725);
PAINT WHITE (-7000 1725);
DISPLAY INVISIBLE (-7000 1725);
FORCEPROP 2 LAST ROOM PVCCIN_CPU1_PWR_VR
J 0
(-7000 1725);
DISPLAY 1.361702 (-7000 1725);
PAINT ORANGE (-7000 1725);
DISPLAY INVISIBLE (-7000 1725);
FORCEPROP 2 LAST CDS_LOCATION C9P2
J 0
(-7000 1675);
DISPLAY 0.617021 (-7000 1675);
PAINT AQUA (-7000 1675);
DISPLAY INVISIBLE (-7000 1675);
FORCEADD OFFPAGE..1
(-6650 1175);
FORCEPROP 2 LAST $XR0 206 
J 0
(-6932 1175);
DISPLAY 0.638298 (-6932 1175);
PAINT MONO (-6932 1175);
FORCEPROP 1 LAST COMMENT_BODY TRUE
J 0
(-6525 1075);
DISPLAY 1.680851 (-6525 1075);
PAINT GREEN (-6525 1075);
DISPLAY INVISIBLE (-6525 1075);
FORCEPROP 1 LAST OFFPAGE TRUE
J 0
(-6325 1050);
DISPLAY 1.680851 (-6325 1050);
PAINT GREEN (-6325 1050);
DISPLAY INVISIBLE (-6325 1050);
FORCEPROP 2 LAST ROOM PVCCIN_CPU1_PWR_VR
J 0
(-7050 1250);
DISPLAY 1.936170 (-7050 1250);
PAINT ORANGE (-7050 1250);
DISPLAY INVISIBLE (-7050 1250);
FORCEPROP 2 LAST PATH I61
J 0
(-6895 1225);
DISPLAY 1.021277 (-6895 1225);
PAINT ORANGE (-6895 1225);
DISPLAY INVISIBLE (-6895 1225);
FORCEPROP 2 LAST BOM_COST PROC_VRD_VCCIN_CPU0
J 0
(-6900 1225);
DISPLAY 1.446809 (-6900 1225);
PAINT MONO (-6900 1225);
DISPLAY INVISIBLE (-6900 1225);
FORCEPROP 2 LAST CDS_LIB mstr_standard
J 0
(-6650 1175);
PAINT ORANGE (-6650 1175);
DISPLAY INVISIBLE (-6650 1175);
FORCEADD VCC_CORE..1
(-6475 1975);
FORCEPROP 3 LASTPIN (-6475 1925) SIG_NAME VR_FET_SW_P12V_STBY_PVCCIN_CPU1\g
J 0
(-6465 1935);
DISPLAY 0.659574 (-6465 1935);
PAINT MONO (-6465 1935);
DISPLAY INVISIBLE (-6465 1935);
FORCEPROP 1 LAST HDL_POWER VR_FET_SW_P12V_STBY_PVCCIN_CPU1
J 1
(-6400 2025);
DISPLAY 0.617021 (-6400 2025);
PAINT GREEN (-6400 2025);
FORCEPROP 1 LAST PATH I62
J 0
(-6425 2000);
DISPLAY 0.872340 (-6425 2000);
PAINT AQUA (-6425 2000);
DISPLAY INVISIBLE (-6425 2000);
FORCEPROP 2 LAST CDS_LIB mstr_symbols
J 0
(-6475 1975);
PAINT ORANGE (-6475 1975);
DISPLAY INVISIBLE (-6475 1975);
FORCEADD GND..1
(-7050 950);
FORCEPROP 3 LASTPIN (-7050 1000) SIG_NAME GND\g
J 0
(-7040 1010);
DISPLAY 0.659574 (-7040 1010);
PAINT MONO (-7040 1010);
DISPLAY INVISIBLE (-7040 1010);
FORCEPROP 2 LAST BOM_COST PROC_VRD_VCCIN_CPU0
J 0
(-7425 1025);
DISPLAY 1.446809 (-7425 1025);
PAINT MONO (-7425 1025);
DISPLAY INVISIBLE (-7425 1025);
FORCEPROP 2 LAST ROOM PVCCIN_CPU1_PWR_VR
J 0
(-7600 1025);
DISPLAY 1.936170 (-7600 1025);
PAINT ORANGE (-7600 1025);
DISPLAY INVISIBLE (-7600 1025);
FORCEPROP 1 LAST VOLTAGE 0
J 0
(-7050 950);
PAINT SKYBLUE (-7050 950);
DISPLAY INVISIBLE (-7050 950);
FORCEPROP 2 LAST CDS_LIB mstr_symbols
J 0
(-7050 950);
PAINT ORANGE (-7050 950);
DISPLAY INVISIBLE (-7050 950);
FORCEPROP 1 LAST SIZE 1B
J 0
(-6975 900);
DISPLAY 1.723404 (-6975 900);
PAINT GREEN (-6975 900);
DISPLAY INVISIBLE (-6975 900);
FORCEPROP 1 LAST PATH I63
J 0
(-6975 950);
DISPLAY 0.872340 (-6975 950);
PAINT AQUA (-6975 950);
DISPLAY INVISIBLE (-6975 950);
FORCEPROP 1 LAST BODY_TYPE PLUMBING
J 0
(-7095 907);
DISPLAY 0.340426 (-7095 907);
PAINT GREEN (-7095 907);
DISPLAY INVISIBLE (-7095 907);
FORCEPROP 1 LAST HDL_POWER GND
J 0
(-7050 1100);
DISPLAY 1.723404 (-7050 1100);
PAINT GREEN (-7050 1100);
DISPLAY INVISIBLE (-7050 1100);
FORCEADD P5V_STBY..1
(-4925 4850);
FORCEPROP 3 LASTPIN (-4925 4800) SIG_NAME P5V_STBY\g
J 0
(-4915 4810);
DISPLAY 0.659574 (-4915 4810);
PAINT MONO (-4915 4810);
DISPLAY INVISIBLE (-4915 4810);
FORCEPROP 1 LAST HDL_POWER P5V_STBY
J 0
(-5225 4725);
DISPLAY 0.872340 (-5225 4725);
PAINT ORANGE (-5225 4725);
DISPLAY INVISIBLE (-5225 4725);
FORCEPROP 1 LAST BODY_TYPE PLUMBING
J 0
(-4970 4807);
DISPLAY 0.340426 (-4970 4807);
PAINT GREEN (-4970 4807);
DISPLAY INVISIBLE (-4970 4807);
FORCEPROP 1 LAST SIZE 1B
J 0
(-4880 4872);
DISPLAY 0.340426 (-4880 4872);
PAINT GREEN (-4880 4872);
DISPLAY INVISIBLE (-4880 4872);
FORCEPROP 2 LAST CDS_LIB mstr_symbols
J 0
(-4925 4850);
PAINT ORANGE (-4925 4850);
DISPLAY INVISIBLE (-4925 4850);
FORCEPROP 1 LAST PATH I64
J 0
(-4880 4852);
DISPLAY 0.340426 (-4880 4852);
PAINT GREEN (-4880 4852);
DISPLAY INVISIBLE (-4880 4852);
FORCEPROP 1 LAST VOLTAGE 5.0V
J 0
(-4970 4807);
DISPLAY 0.340426 (-4970 4807);
PAINT SKYBLUE (-4970 4807);
DISPLAY INVISIBLE (-4970 4807);
FORCEADD P5V_STBY..1
(-5000 2150);
FORCEPROP 3 LASTPIN (-5000 2100) SIG_NAME P5V_STBY\g
J 0
(-4990 2110);
DISPLAY 0.659574 (-4990 2110);
PAINT MONO (-4990 2110);
DISPLAY INVISIBLE (-4990 2110);
FORCEPROP 1 LAST HDL_POWER P5V_STBY
J 0
(-5300 2025);
DISPLAY 0.872340 (-5300 2025);
PAINT ORANGE (-5300 2025);
DISPLAY INVISIBLE (-5300 2025);
FORCEPROP 1 LAST BODY_TYPE PLUMBING
J 0
(-5045 2107);
DISPLAY 0.340426 (-5045 2107);
PAINT GREEN (-5045 2107);
DISPLAY INVISIBLE (-5045 2107);
FORCEPROP 1 LAST VOLTAGE 5.0V
J 0
(-5045 2107);
DISPLAY 0.340426 (-5045 2107);
PAINT SKYBLUE (-5045 2107);
DISPLAY INVISIBLE (-5045 2107);
FORCEPROP 1 LAST SIZE 1B
J 0
(-4955 2172);
DISPLAY 0.340426 (-4955 2172);
PAINT GREEN (-4955 2172);
DISPLAY INVISIBLE (-4955 2172);
FORCEPROP 2 LAST CDS_LIB mstr_symbols
J 0
(-5000 2150);
PAINT ORANGE (-5000 2150);
DISPLAY INVISIBLE (-5000 2150);
FORCEPROP 1 LAST PATH I65
J 0
(-4955 2152);
DISPLAY 0.340426 (-4955 2152);
PAINT GREEN (-4955 2152);
DISPLAY INVISIBLE (-4955 2152);
FORCEADD CAP_A..1
(-400 3400);
FORCEPROP 1 LASTPIN (-400 3500) $PN 1
J 0
(-390 3480);
DISPLAY 0.617021 (-390 3480);
PAINT ORANGE (-390 3480);
FORCEPROP 1 LAST MATERIAL X6S
J 0
(-350 3350);
DISPLAY 0.617021 (-350 3350);
PAINT SKYBLUE (-350 3350);
FORCEPROP 1 LASTPIN (-400 3300) $PN 2
J 0
(-390 3280);
DISPLAY 0.617021 (-390 3280);
PAINT ORANGE (-390 3280);
FORCEPROP 1 LAST TOLERANCE 20%
J 0
(-350 3400);
DISPLAY 0.617021 (-350 3400);
PAINT SKYBLUE (-350 3400);
FORCEPROP 1 LAST VOLTAGE 4V
J 0
(-350 3450);
DISPLAY 0.617021 (-350 3450);
PAINT SKYBLUE (-350 3450);
FORCEPROP 1 LAST VALUE 22.0UF
J 0
(-350 3500);
DISPLAY 0.617021 (-350 3500);
PAINT SKYBLUE (-350 3500);
FORCEPROP 1 LAST LOCATION C9P10
J 0
(-350 3550);
DISPLAY 0.617021 (-350 3550);
PAINT AQUA (-350 3550);
FORCEPROP 1 LAST PACK_TYPE 0603V
J 0
(-350 3250);
DISPLAY 0.617021 (-350 3250);
PAINT SKYBLUE (-350 3250);
FORCEPROP 1 LAST PART_NUMBER E15431-004
J 0
(-350 3300);
DISPLAY 0.617021 (-350 3300);
PAINT BLUE (-350 3300);
FORCEPROP 0 LAST GROUP PWR_MLCC_CAP
J 0
(-344 3137);
DISPLAY 0.638298 (-344 3137);
PAINT BROWN (-344 3137);
DISPLAY BOTH (-344 3137);
FORCEPROP 2 LAST SEC_TYPE 0603V
J 0
(-350 3600);
DISPLAY 1.021277 (-350 3600);
PAINT ORANGE (-350 3600);
DISPLAY INVISIBLE (-350 3600);
FORCEPROP 2 LAST SEC 1
J 0
(-350 3600);
DISPLAY 0.680851 (-350 3600);
PAINT MONO (-350 3600);
DISPLAY INVISIBLE (-350 3600);
FORCEPROP 2 LAST CDS_SEC 1
J 0
(-350 3550);
PAINT ORANGE (-350 3550);
DISPLAY INVISIBLE (-350 3550);
FORCEPROP 1 LAST PATH I66
J 0
(-350 3550);
DISPLAY 0.978723 (-350 3550);
PAINT WHITE (-350 3550);
DISPLAY INVISIBLE (-350 3550);
FORCEPROP 2 LAST CDS_LOCATION C9P10
J 0
(-350 3500);
DISPLAY 0.617021 (-350 3500);
PAINT AQUA (-350 3500);
DISPLAY INVISIBLE (-350 3500);
FORCEPROP 2 LAST CDS_LIB dev_discrete
J 0
(-400 3400);
PAINT ORANGE (-400 3400);
DISPLAY INVISIBLE (-400 3400);
FORCEADD CAP_A..1
(-350 800);
FORCEPROP 1 LASTPIN (-350 900) $PN 1
J 0
(-340 880);
DISPLAY 0.617021 (-340 880);
PAINT ORANGE (-340 880);
FORCEPROP 1 LASTPIN (-350 700) $PN 2
J 0
(-340 680);
DISPLAY 0.617021 (-340 680);
PAINT ORANGE (-340 680);
FORCEPROP 1 LAST VALUE 22.0UF
J 0
(-300 850);
DISPLAY 0.617021 (-300 850);
PAINT SKYBLUE (-300 850);
FORCEPROP 1 LAST VOLTAGE 4V
J 0
(-300 800);
DISPLAY 0.617021 (-300 800);
PAINT SKYBLUE (-300 800);
FORCEPROP 1 LAST TOLERANCE 20%
J 0
(-300 750);
DISPLAY 0.617021 (-300 750);
PAINT SKYBLUE (-300 750);
FORCEPROP 1 LAST MATERIAL X6S
J 0
(-300 700);
DISPLAY 0.617021 (-300 700);
PAINT SKYBLUE (-300 700);
FORCEPROP 1 LAST PART_NUMBER E15431-004
J 0
(-300 650);
DISPLAY 0.617021 (-300 650);
PAINT BLUE (-300 650);
FORCEPROP 1 LAST PACK_TYPE 0603V
J 0
(-300 600);
DISPLAY 0.617021 (-300 600);
PAINT SKYBLUE (-300 600);
FORCEPROP 0 LAST GROUP PWR_MLCC_CAP
J 0
(-294 512);
DISPLAY 0.638298 (-294 512);
PAINT BROWN (-294 512);
DISPLAY BOTH (-294 512);
FORCEPROP 1 LAST LOCATION C9R2
J 0
(-300 900);
DISPLAY 0.617021 (-300 900);
PAINT AQUA (-300 900);
FORCEPROP 2 LAST SEC_TYPE 0603V
J 0
(-300 1000);
DISPLAY 1.021277 (-300 1000);
PAINT ORANGE (-300 1000);
DISPLAY INVISIBLE (-300 1000);
FORCEPROP 2 LAST SEC 1
J 0
(-300 1000);
DISPLAY 0.680851 (-300 1000);
PAINT MONO (-300 1000);
DISPLAY INVISIBLE (-300 1000);
FORCEPROP 1 LAST PATH I67
J 0
(-300 950);
DISPLAY 0.978723 (-300 950);
PAINT WHITE (-300 950);
DISPLAY INVISIBLE (-300 950);
FORCEPROP 2 LAST CDS_SEC 1
J 0
(-300 950);
PAINT ORANGE (-300 950);
DISPLAY INVISIBLE (-300 950);
FORCEPROP 2 LAST CDS_LOCATION C9R2
J 0
(-300 900);
DISPLAY 0.617021 (-300 900);
PAINT AQUA (-300 900);
DISPLAY INVISIBLE (-300 900);
FORCEPROP 2 LAST CDS_LIB dev_discrete
J 0
(-350 800);
PAINT ORANGE (-350 800);
DISPLAY INVISIBLE (-350 800);
FORCEADD RES..2
(-1000 2575);
FORCEPROP 1 LAST PACK_TYPE 0603
J 0
(-960 2400);
DISPLAY 0.617021 (-960 2400);
PAINT SKYBLUE (-960 2400);
FORCEPROP 1 LAST TOLERANCE 1%
J 0
(-955 2600);
DISPLAY 0.617021 (-955 2600);
PAINT SKYBLUE (-955 2600);
FORCEPROP 1 LASTPIN (-1000 2675) $PN 1
J 0
(-995 2637);
DISPLAY 0.617021 (-995 2637);
PAINT ORANGE (-995 2637);
FORCEPROP 1 LASTPIN (-1000 2475) $PN 2
J 0
(-995 2485);
DISPLAY 0.617021 (-995 2485);
PAINT ORANGE (-995 2485);
FORCEPROP 1 LAST VALUE 100.0
J 0
(-955 2650);
DISPLAY 0.617021 (-955 2650);
PAINT SKYBLUE (-955 2650);
FORCEPROP 1 LAST PART_NUMBER G22026-038
J 0
(-960 2450);
DISPLAY 0.617021 (-960 2450);
PAINT BLUE (-960 2450);
FORCEPROP 1 LAST MATERIAL CHIP
J 0
(-960 2500);
DISPLAY 0.617021 (-960 2500);
PAINT SKYBLUE (-960 2500);
FORCEPROP 1 LAST WATTAGE 1/10W
J 0
(-960 2550);
DISPLAY 0.617021 (-960 2550);
PAINT SKYBLUE (-960 2550);
FORCEPROP 1 LAST LOCATION R1E3
J 0
(-955 2700);
DISPLAY 0.617021 (-955 2700);
PAINT AQUA (-955 2700);
FORCEPROP 2 LAST SEC_TYPE 0603
J 0
(-935 2810);
DISPLAY 1.021277 (-935 2810);
PAINT ORANGE (-935 2810);
DISPLAY INVISIBLE (-935 2810);
FORCEPROP 2 LAST SEC 1
J 0
(-935 2810);
DISPLAY 0.680851 (-935 2810);
PAINT MONO (-935 2810);
DISPLAY INVISIBLE (-935 2810);
FORCEPROP 2 LAST BOM_COST PROC_VRD_VCCIN_CPU0
J 0
(-950 2750);
PAINT MONO (-950 2750);
DISPLAY INVISIBLE (-950 2750);
FORCEPROP 2 LAST CDS_LOCATION R1E3
J 0
(-955 2700);
DISPLAY 0.617021 (-955 2700);
PAINT AQUA (-955 2700);
DISPLAY INVISIBLE (-955 2700);
FORCEPROP 1 LAST PATH I7
J 0
(-950 2750);
DISPLAY 0.978723 (-950 2750);
PAINT WHITE (-950 2750);
DISPLAY INVISIBLE (-950 2750);
FORCEPROP 2 LAST ROOM PVCCIN_CPU1_DECAP_VR
J 0
(-950 2750);
PAINT MONO (-950 2750);
DISPLAY INVISIBLE (-950 2750);
FORCEPROP 2 LAST CDS_LIB mstr_discrete
J 0
(-1000 2575);
PAINT ORANGE (-1000 2575);
DISPLAY INVISIBLE (-1000 2575);
FORCEADD OFFPAGE..2
(-900 4425);
FORCEPROP 2 LAST $XR0 206 
J 0
(-711 4425);
DISPLAY 0.638298 (-711 4425);
PAINT MONO (-711 4425);
FORCEPROP 1 LAST COMMENT_BODY TRUE
J 0
(-945 4330);
DISPLAY 1.723404 (-945 4330);
PAINT GREEN (-945 4330);
DISPLAY INVISIBLE (-945 4330);
FORCEPROP 1 LAST OFFPAGE TRUE
J 0
(-575 4300);
DISPLAY 1.723404 (-575 4300);
PAINT GREEN (-575 4300);
DISPLAY INVISIBLE (-575 4300);
FORCEPROP 2 LAST BOM_COST PROC_VRD_VCCIN_CPU0
J 0
(-700 4475);
DISPLAY 1.446809 (-700 4475);
PAINT MONO (-700 4475);
DISPLAY INVISIBLE (-700 4475);
FORCEPROP 2 LAST PATH I70
J 0
(-725 4500);
DISPLAY 1.021277 (-725 4500);
PAINT ORANGE (-725 4500);
DISPLAY INVISIBLE (-725 4500);
FORCEPROP 2 LAST CDS_LIB mstr_standard
J 0
(-900 4425);
PAINT ORANGE (-900 4425);
DISPLAY INVISIBLE (-900 4425);
FORCEPROP 2 LAST ROOM PVCCIN_CPU1_PWR_VR
J 0
(-1300 4500);
DISPLAY 1.936170 (-1300 4500);
PAINT ORANGE (-1300 4500);
DISPLAY INVISIBLE (-1300 4500);
FORCEADD IR354XX..1
(-3250 1275);
FORCEPROP 2 LASTPIN (-2750 975) $PN 10
J 0
(-2740 985);
DISPLAY 0.617021 (-2740 985);
PAINT ORANGE (-2740 985);
FORCEPROP 2 LASTPIN (-2750 1625) $PN 37
J 0
(-2740 1635);
DISPLAY 0.617021 (-2740 1635);
PAINT ORANGE (-2740 1635);
FORCEPROP 2 LASTPIN (-2750 875) $PN 2
J 0
(-2740 885);
DISPLAY 0.617021 (-2740 885);
PAINT ORANGE (-2740 885);
FORCEPROP 2 LASTPIN (-2750 1325) $PN 36
J 0
(-2740 1335);
DISPLAY 0.617021 (-2740 1335);
PAINT ORANGE (-2740 1335);
FORCEPROP 1 LAST PART_NUMBER H73688-001
J 0
(-3325 575);
DISPLAY 0.617021 (-3325 575);
PAINT BLUE (-3325 575);
FORCEPROP 2 LASTPIN (-3750 1775) $PN 30
J 2
(-3760 1785);
DISPLAY 0.617021 (-3760 1785);
PAINT ORANGE (-3760 1785);
FORCEPROP 2 LASTPIN (-3750 1725) $PN 25
J 2
(-3760 1735);
DISPLAY 0.617021 (-3760 1735);
PAINT ORANGE (-3760 1735);
FORCEPROP 2 LASTPIN (-2750 825) $PN 40
J 0
(-2740 835);
DISPLAY 0.617021 (-2740 835);
PAINT ORANGE (-2740 835);
FORCEPROP 2 LASTPIN (-2750 775) $PN 7
J 0
(-2740 785);
DISPLAY 0.617021 (-2740 785);
PAINT ORANGE (-2740 785);
FORCEPROP 2 LASTPIN (-2750 725) $PN 5
J 0
(-2740 735);
DISPLAY 0.617021 (-2740 735);
PAINT ORANGE (-2740 735);
FORCEPROP 2 LASTPIN (-3750 1825) $PN 3
J 2
(-3760 1835);
DISPLAY 0.617021 (-3760 1835);
PAINT ORANGE (-3760 1835);
FORCEPROP 2 LASTPIN (-3750 1625) $PN 4
J 2
(-3760 1635);
DISPLAY 0.617021 (-3760 1635);
PAINT ORANGE (-3760 1635);
FORCEPROP 2 LASTPIN (-3750 1425) $PN 1
J 2
(-3760 1435);
DISPLAY 0.617021 (-3760 1435);
PAINT ORANGE (-3760 1435);
FORCEPROP 2 LASTPIN (-3750 1325) $PN 41
J 2
(-3760 1335);
DISPLAY 0.617021 (-3760 1335);
PAINT ORANGE (-3760 1335);
FORCEPROP 2 LASTPIN (-3750 1275) $PN 6
J 2
(-3760 1285);
DISPLAY 0.617021 (-3760 1285);
PAINT ORANGE (-3760 1285);
FORCEPROP 2 LASTPIN (-3750 1175) $PN 34
J 2
(-3760 1185);
DISPLAY 0.617021 (-3760 1185);
PAINT ORANGE (-3760 1185);
FORCEPROP 2 LASTPIN (-3750 1525) $PN 35
J 2
(-3760 1535);
DISPLAY 0.617021 (-3760 1535);
PAINT ORANGE (-3760 1535);
FORCEPROP 2 LASTPIN (-2750 1825) $PN 38
J 0
(-2740 1835);
DISPLAY 0.617021 (-2740 1835);
PAINT ORANGE (-2740 1835);
FORCEPROP 2 LASTPIN (-2750 1575) $PN 31
J 0
(-2740 1585);
DISPLAY 0.617021 (-2740 1585);
PAINT ORANGE (-2740 1585);
FORCEPROP 2 LASTPIN (-3750 975) $PN 33
J 2
(-3760 985);
DISPLAY 0.617021 (-3760 985);
PAINT ORANGE (-3760 985);
FORCEPROP 2 LASTPIN (-3750 1075) $PN 39
J 2
(-3760 1085);
DISPLAY 0.617021 (-3760 1085);
PAINT ORANGE (-3760 1085);
FORCEPROP 2 LASTPIN (-3750 925) $PN 32
J 2
(-3760 935);
DISPLAY 0.617021 (-3760 935);
PAINT ORANGE (-3760 935);
FORCEPROP 1 LAST MATERIAL IC
J 0
(-3700 2025);
DISPLAY 0.617021 (-3700 2025);
PAINT SKYBLUE (-3700 2025);
FORCEPROP 1 LAST LOCATION EU1D1
J 0
(-3650 2000);
DISPLAY 0.617021 (-3650 2000);
PAINT AQUA (-3650 2000);
FORCEPROP 2 LAST SEC_TYPE SM
J 0
(-3250 2075);
DISPLAY 1.021277 (-3250 2075);
PAINT ORANGE (-3250 2075);
DISPLAY INVISIBLE (-3250 2075);
FORCEPROP 2 LAST SEC 1
J 0
(-3250 2075);
DISPLAY 0.680851 (-3250 2075);
PAINT MONO (-3250 2075);
DISPLAY INVISIBLE (-3250 2075);
FORCEPROP 1 LAST PACK_TYPE SM
J 0
(-3700 2125);
PAINT SKYBLUE (-3700 2125);
DISPLAY INVISIBLE (-3700 2125);
FORCEPROP 2 LAST ROOM PVCCIN_CPU1_PWR_VR
J 0
(-3650 2050);
DISPLAY 1.361702 (-3650 2050);
PAINT ORANGE (-3650 2050);
DISPLAY INVISIBLE (-3650 2050);
FORCEPROP 1 LAST PATH I71
J 0
(-3250 2025);
PAINT GREEN (-3250 2025);
DISPLAY INVISIBLE (-3250 2025);
FORCEPROP 2 LAST CDS_LIB mstr_discrete
J 0
(-3250 1275);
PAINT ORANGE (-3250 1275);
DISPLAY INVISIBLE (-3250 1275);
FORCEPROP 2 LAST CDS_LOCATION EU1D1
J 0
(-3650 2000);
DISPLAY 0.617021 (-3650 2000);
PAINT AQUA (-3650 2000);
DISPLAY INVISIBLE (-3650 2000);
FORCEPROP 1 LAST VALUE IR35411
J 1
(-3250 1900);
DISPLAY 0.617021 (-3250 1900);
PAINT SKYBLUE (-3250 1900);
DISPLAY INVISIBLE (-3250 1900);
FORCEADD OFFPAGE..2
(-850 2125);
FORCEPROP 2 LAST $XR0 206 
J 0
(-661 2125);
DISPLAY 0.638298 (-661 2125);
PAINT MONO (-661 2125);
FORCEPROP 1 LAST COMMENT_BODY TRUE
J 0
(-895 2030);
DISPLAY 1.723404 (-895 2030);
PAINT GREEN (-895 2030);
DISPLAY INVISIBLE (-895 2030);
FORCEPROP 1 LAST OFFPAGE TRUE
J 0
(-525 2000);
DISPLAY 1.723404 (-525 2000);
PAINT GREEN (-525 2000);
DISPLAY INVISIBLE (-525 2000);
FORCEPROP 2 LAST BOM_COST PROC_VRD_VCCIN_CPU0
J 0
(-650 2175);
DISPLAY 1.446809 (-650 2175);
PAINT MONO (-650 2175);
DISPLAY INVISIBLE (-650 2175);
FORCEPROP 2 LAST PATH I72
J 0
(-675 2200);
DISPLAY 1.021277 (-675 2200);
PAINT ORANGE (-675 2200);
DISPLAY INVISIBLE (-675 2200);
FORCEPROP 2 LAST CDS_LIB mstr_standard
J 0
(-850 2125);
PAINT ORANGE (-850 2125);
DISPLAY INVISIBLE (-850 2125);
FORCEPROP 2 LAST ROOM PVCCIN_CPU1_PWR_VR
J 0
(-1250 2200);
DISPLAY 1.936170 (-1250 2200);
PAINT ORANGE (-1250 2200);
DISPLAY INVISIBLE (-1250 2200);
FORCEADD RES..2
(-625 1450);
FORCEPROP 1 LAST LOCATION R1D54
J 0
(-580 1575);
DISPLAY 0.617021 (-580 1575);
PAINT AQUA (-580 1575);
FORCEPROP 1 LASTPIN (-625 1550) $PN 1
J 0
(-620 1512);
DISPLAY 0.617021 (-620 1512);
PAINT ORANGE (-620 1512);
FORCEPROP 1 LAST TOLERANCE 1%
J 0
(-580 1475);
DISPLAY 0.617021 (-580 1475);
PAINT SKYBLUE (-580 1475);
FORCEPROP 1 LAST VALUE 68.1K
J 0
(-580 1525);
DISPLAY 0.617021 (-580 1525);
PAINT SKYBLUE (-580 1525);
FORCEPROP 1 LAST PACK_TYPE 0402
J 0
(-585 1275);
DISPLAY 0.617021 (-585 1275);
PAINT SKYBLUE (-585 1275);
FORCEPROP 1 LAST WATTAGE 1/16W
J 0
(-585 1425);
DISPLAY 0.617021 (-585 1425);
PAINT SKYBLUE (-585 1425);
FORCEPROP 1 LASTPIN (-625 1350) $PN 2
J 0
(-620 1360);
DISPLAY 0.617021 (-620 1360);
PAINT ORANGE (-620 1360);
FORCEPROP 1 LAST PART_NUMBER G21796-187
J 0
(-585 1325);
DISPLAY 0.617021 (-585 1325);
PAINT BLUE (-585 1325);
FORCEPROP 1 LAST MATERIAL EMPTY
J 0
(-585 1375);
DISPLAY 0.617021 (-585 1375);
PAINT RED (-585 1375);
FORCEPROP 1 LAST PATH I75
J 0
(-575 1625);
DISPLAY 0.978723 (-575 1625);
PAINT WHITE (-575 1625);
DISPLAY INVISIBLE (-575 1625);
FORCEPROP 2 LAST $SEC 1
J 0
(-575 1675);
PAINT MONO (-575 1675);
DISPLAY INVISIBLE (-575 1675);
FORCEPROP 2 LAST CDS_SEC 1
J 0
(-575 1675);
PAINT MONO (-575 1675);
DISPLAY INVISIBLE (-575 1675);
FORCEPROP 2 LAST CDS_LIB mstr_discrete
J 0
(-625 1450);
PAINT ORANGE (-625 1450);
DISPLAY INVISIBLE (-625 1450);
FORCEADD RES..2
(-700 4075);
FORCEPROP 1 LAST LOCATION R1D55
J 0
(-655 4200);
DISPLAY 0.617021 (-655 4200);
PAINT AQUA (-655 4200);
FORCEPROP 1 LASTPIN (-700 4175) $PN 1
J 0
(-695 4137);
DISPLAY 0.617021 (-695 4137);
PAINT ORANGE (-695 4137);
FORCEPROP 1 LASTPIN (-700 3975) $PN 2
J 0
(-695 3985);
DISPLAY 0.617021 (-695 3985);
PAINT ORANGE (-695 3985);
FORCEPROP 1 LAST PACK_TYPE 0402
J 0
(-660 3900);
DISPLAY 0.617021 (-660 3900);
PAINT SKYBLUE (-660 3900);
FORCEPROP 1 LAST VALUE 68.1K
J 0
(-655 4150);
DISPLAY 0.617021 (-655 4150);
PAINT SKYBLUE (-655 4150);
FORCEPROP 1 LAST TOLERANCE 1%
J 0
(-655 4100);
DISPLAY 0.617021 (-655 4100);
PAINT SKYBLUE (-655 4100);
FORCEPROP 1 LAST WATTAGE 1/16W
J 0
(-660 4050);
DISPLAY 0.617021 (-660 4050);
PAINT SKYBLUE (-660 4050);
FORCEPROP 1 LAST MATERIAL EMPTY
J 0
(-660 4000);
DISPLAY 0.617021 (-660 4000);
PAINT RED (-660 4000);
FORCEPROP 1 LAST PART_NUMBER G21796-187
J 0
(-660 3950);
DISPLAY 0.617021 (-660 3950);
PAINT BLUE (-660 3950);
FORCEPROP 2 LAST CDS_SEC 1
J 0
(-650 4300);
PAINT MONO (-650 4300);
DISPLAY INVISIBLE (-650 4300);
FORCEPROP 2 LAST $SEC 1
J 0
(-650 4300);
PAINT MONO (-650 4300);
DISPLAY INVISIBLE (-650 4300);
FORCEPROP 1 LAST PATH I76
J 0
(-650 4250);
DISPLAY 0.978723 (-650 4250);
PAINT WHITE (-650 4250);
DISPLAY INVISIBLE (-650 4250);
FORCEPROP 2 LAST CDS_LIB mstr_discrete
J 0
(-700 4075);
PAINT ORANGE (-700 4075);
DISPLAY INVISIBLE (-700 4075);
FORCEADD GND..1
(-700 3900);
FORCEPROP 3 LASTPIN (-700 3950) SIG_NAME GND\g
J 0
(-690 3960);
DISPLAY 0.659574 (-690 3960);
PAINT MONO (-690 3960);
DISPLAY INVISIBLE (-690 3960);
FORCEPROP 2 LAST ROOM PVCCIN_CPU1_PWR_VR
J 0
(-1250 3975);
DISPLAY 1.936170 (-1250 3975);
PAINT ORANGE (-1250 3975);
DISPLAY INVISIBLE (-1250 3975);
FORCEPROP 2 LAST BOM_COST PROC_VRD_VCCIN_CPU0
J 0
(-1075 3975);
DISPLAY 1.446809 (-1075 3975);
PAINT MONO (-1075 3975);
DISPLAY INVISIBLE (-1075 3975);
FORCEPROP 1 LAST PATH I77
J 0
(-625 3900);
DISPLAY 0.872340 (-625 3900);
PAINT AQUA (-625 3900);
DISPLAY INVISIBLE (-625 3900);
FORCEPROP 1 LAST SIZE 1B
J 0
(-625 3850);
DISPLAY 1.723404 (-625 3850);
PAINT GREEN (-625 3850);
DISPLAY INVISIBLE (-625 3850);
FORCEPROP 2 LAST CDS_LIB mstr_symbols
J 0
(-700 3900);
PAINT ORANGE (-700 3900);
DISPLAY INVISIBLE (-700 3900);
FORCEPROP 1 LAST VOLTAGE 0
J 0
(-700 3900);
PAINT SKYBLUE (-700 3900);
DISPLAY INVISIBLE (-700 3900);
FORCEPROP 1 LAST BODY_TYPE PLUMBING
J 0
(-745 3857);
DISPLAY 0.340426 (-745 3857);
PAINT GREEN (-745 3857);
DISPLAY INVISIBLE (-745 3857);
FORCEPROP 1 LAST HDL_POWER GND
J 0
(-700 4050);
DISPLAY 1.723404 (-700 4050);
PAINT GREEN (-700 4050);
DISPLAY INVISIBLE (-700 4050);
FORCEADD GND..1
(-625 1225);
FORCEPROP 3 LASTPIN (-625 1275) SIG_NAME GND\g
J 0
(-615 1285);
DISPLAY 0.659574 (-615 1285);
PAINT MONO (-615 1285);
DISPLAY INVISIBLE (-615 1285);
FORCEPROP 1 LAST HDL_POWER GND
J 0
(-625 1375);
DISPLAY 1.723404 (-625 1375);
PAINT GREEN (-625 1375);
DISPLAY INVISIBLE (-625 1375);
FORCEPROP 1 LAST BODY_TYPE PLUMBING
J 0
(-670 1182);
DISPLAY 0.340426 (-670 1182);
PAINT GREEN (-670 1182);
DISPLAY INVISIBLE (-670 1182);
FORCEPROP 1 LAST VOLTAGE 0
J 0
(-625 1225);
PAINT SKYBLUE (-625 1225);
DISPLAY INVISIBLE (-625 1225);
FORCEPROP 1 LAST SIZE 1B
J 0
(-550 1175);
DISPLAY 1.723404 (-550 1175);
PAINT GREEN (-550 1175);
DISPLAY INVISIBLE (-550 1175);
FORCEPROP 2 LAST CDS_LIB mstr_symbols
J 0
(-625 1225);
PAINT ORANGE (-625 1225);
DISPLAY INVISIBLE (-625 1225);
FORCEPROP 1 LAST PATH I78
J 0
(-550 1225);
DISPLAY 0.872340 (-550 1225);
PAINT AQUA (-550 1225);
DISPLAY INVISIBLE (-550 1225);
FORCEPROP 2 LAST BOM_COST PROC_VRD_VCCIN_CPU0
J 0
(-1000 1300);
DISPLAY 1.446809 (-1000 1300);
PAINT MONO (-1000 1300);
DISPLAY INVISIBLE (-1000 1300);
FORCEPROP 2 LAST ROOM PVCCIN_CPU1_PWR_VR
J 0
(-1175 1300);
DISPLAY 1.936170 (-1175 1300);
PAINT ORANGE (-1175 1300);
DISPLAY INVISIBLE (-1175 1300);
FORCEADD GND..1
(-3975 3125);
FORCEPROP 3 LASTPIN (-3975 3175) SIG_NAME GND\g
J 0
(-3965 3185);
DISPLAY 0.659574 (-3965 3185);
PAINT MONO (-3965 3185);
DISPLAY INVISIBLE (-3965 3185);
FORCEPROP 1 LAST HDL_POWER GND
J 0
(-3975 3275);
DISPLAY 1.723404 (-3975 3275);
PAINT GREEN (-3975 3275);
DISPLAY INVISIBLE (-3975 3275);
FORCEPROP 1 LAST BODY_TYPE PLUMBING
J 0
(-4020 3082);
DISPLAY 0.340426 (-4020 3082);
PAINT GREEN (-4020 3082);
DISPLAY INVISIBLE (-4020 3082);
FORCEPROP 2 LAST ROOM PVCCIN_CPU0_PWR_VR
J 0
(-4525 3200);
DISPLAY 1.936170 (-4525 3200);
PAINT ORANGE (-4525 3200);
DISPLAY INVISIBLE (-4525 3200);
FORCEPROP 2 LAST BOM_COST PROC_VRD_VCCIN_CPU0
J 0
(-4350 3200);
DISPLAY 1.446809 (-4350 3200);
PAINT MONO (-4350 3200);
DISPLAY INVISIBLE (-4350 3200);
FORCEPROP 1 LAST SIZE 1B
J 0
(-3900 3075);
DISPLAY 1.723404 (-3900 3075);
PAINT GREEN (-3900 3075);
DISPLAY INVISIBLE (-3900 3075);
FORCEPROP 1 LAST VOLTAGE 0
J 0
(-3975 3125);
PAINT SKYBLUE (-3975 3125);
DISPLAY INVISIBLE (-3975 3125);
FORCEPROP 1 LAST PATH I79
J 0
(-3900 3125);
DISPLAY 0.872340 (-3900 3125);
PAINT AQUA (-3900 3125);
DISPLAY INVISIBLE (-3900 3125);
FORCEPROP 2 LAST CDS_LIB mstr_symbols
J 0
(-3975 3125);
PAINT MONO (-3975 3125);
DISPLAY INVISIBLE (-3975 3125);
FORCEADD PVCCIN_CPU1..1
(-400 3700);
FORCEPROP 3 LASTPIN (-400 3650) SIG_NAME PVCCIN_CPU1\g
J 0
(-390 3660);
DISPLAY 0.659574 (-390 3660);
PAINT MONO (-390 3660);
DISPLAY INVISIBLE (-390 3660);
FORCEPROP 1 LAST HDL_POWER PVCCIN_CPU1
J 1
(-400 3750);
DISPLAY 0.872340 (-400 3750);
PAINT GREEN (-400 3750);
DISPLAY INVISIBLE (-400 3750);
FORCEPROP 1 LAST BODY_TYPE PLUMBING
J 0
(-445 3657);
DISPLAY 0.340426 (-445 3657);
PAINT GREEN (-445 3657);
DISPLAY INVISIBLE (-445 3657);
FORCEPROP 2 LAST CDS_LIB mstr_symbols
J 0
(-400 3700);
PAINT ORANGE (-400 3700);
DISPLAY INVISIBLE (-400 3700);
FORCEPROP 1 LAST VOLTAGE 2.0V
J 0
(-445 3657);
DISPLAY 0.340426 (-445 3657);
PAINT SKYBLUE (-445 3657);
DISPLAY INVISIBLE (-445 3657);
FORCEPROP 1 LAST PATH I8
J 0
(-350 3725);
DISPLAY 0.872340 (-350 3725);
PAINT AQUA (-350 3725);
DISPLAY INVISIBLE (-350 3725);
FORCEADD CAP_A..1
(-3975 3375);
FORCEPROP 1 LASTPIN (-3975 3275) $PN 2
J 0
(-3965 3255);
DISPLAY 0.787234 (-3965 3255);
PAINT ORANGE (-3965 3255);
FORCEPROP 0 LAST POP NOPOP
J 0
(-3928 3107);
DISPLAY 1.021277 (-3928 3107);
PAINT RED (-3928 3107);
FORCEPROP 1 LAST PACK_TYPE 0402V
J 0
(-3925 3175);
DISPLAY 0.617021 (-3925 3175);
PAINT SKYBLUE (-3925 3175);
FORCEPROP 1 LAST PART_NUMBER A36096-030
J 0
(-3925 3225);
DISPLAY 0.617021 (-3925 3225);
PAINT BLUE (-3925 3225);
FORCEPROP 1 LAST MATERIAL X7R
J 0
(-3925 3275);
DISPLAY 0.617021 (-3925 3275);
PAINT SKYBLUE (-3925 3275);
FORCEPROP 1 LAST TOLERANCE 10%
J 0
(-3925 3325);
DISPLAY 0.617021 (-3925 3325);
PAINT SKYBLUE (-3925 3325);
FORCEPROP 1 LAST VOLTAGE 16V
J 0
(-3925 3375);
DISPLAY 0.617021 (-3925 3375);
PAINT SKYBLUE (-3925 3375);
FORCEPROP 1 LAST VALUE 0.1UF
J 0
(-3925 3425);
DISPLAY 0.617021 (-3925 3425);
PAINT SKYBLUE (-3925 3425);
FORCEPROP 1 LASTPIN (-3975 3475) $PN 1
J 0
(-3965 3455);
DISPLAY 0.787234 (-3965 3455);
PAINT ORANGE (-3965 3455);
FORCEPROP 1 LAST LOCATION CT16
J 0
(-3925 3475);
DISPLAY 0.617021 (-3925 3475);
PAINT AQUA (-3925 3475);
FORCEPROP 2 LAST ROOM PVCCIN_CPU0_PWR_VR
J 0
(-3925 3525);
DISPLAY 1.361702 (-3925 3525);
PAINT ORANGE (-3925 3525);
DISPLAY INVISIBLE (-3925 3525);
FORCEPROP 1 LAST PATH I80
J 0
(-3925 3525);
DISPLAY 0.978723 (-3925 3525);
PAINT WHITE (-3925 3525);
DISPLAY INVISIBLE (-3925 3525);
FORCEPROP 2 LAST CDS_LIB dev_discrete
J 0
(-3975 3375);
PAINT MONO (-3975 3375);
DISPLAY INVISIBLE (-3975 3375);
FORCEPROP 0 LAST SEC 1
J 0
(-3925 3525);
DISPLAY 0.680851 (-3925 3525);
PAINT MONO (-3925 3525);
DISPLAY INVISIBLE (-3925 3525);
FORCEPROP 2 LAST SEC_TYPE 0402V
J 0
(-3925 3575);
DISPLAY 1.021277 (-3925 3575);
PAINT ORANGE (-3925 3575);
DISPLAY INVISIBLE (-3925 3575);
FORCEADD CAP..1
(-2050 3900);
FORCEPROP 1 LASTPIN (-2050 4000) $PN 1
J 0
(-2040 3980);
DISPLAY 0.787234 (-2040 3980);
PAINT ORANGE (-2040 3980);
FORCEPROP 1 LASTPIN (-2050 3800) $PN 2
J 0
(-2040 3780);
DISPLAY 0.787234 (-2040 3780);
PAINT ORANGE (-2040 3780);
FORCEPROP 1 LAST LOCATION CTI7
J 0
(-2175 3950);
DISPLAY 0.617021 (-2175 3950);
PAINT AQUA (-2175 3950);
FORCEPROP 1 LAST VOLTAGE 50V
J 0
(-2000 3900);
DISPLAY 0.617021 (-2000 3900);
PAINT SKYBLUE (-2000 3900);
FORCEPROP 1 LAST TOLERANCE 10%
J 0
(-2000 3850);
DISPLAY 0.617021 (-2000 3850);
PAINT SKYBLUE (-2000 3850);
FORCEPROP 1 LAST MATERIAL X7R
J 0
(-2000 3800);
DISPLAY 0.617021 (-2000 3800);
PAINT SKYBLUE (-2000 3800);
FORCEPROP 0 LAST POP NOPOP
J 0
(-1925 3875);
DISPLAY 1.021277 (-1925 3875);
PAINT RED (-1925 3875);
FORCEPROP 1 LAST VALUE 1000PF
J 0
(-2000 3950);
DISPLAY 0.617021 (-2000 3950);
PAINT SKYBLUE (-2000 3950);
FORCEPROP 1 LAST PART_NUMBER A36096-046
J 0
(-2000 3750);
DISPLAY 0.617021 (-2000 3750);
PAINT BLUE (-2000 3750);
FORCEPROP 1 LAST PACK_TYPE 0402LF
J 0
(-2000 3700);
DISPLAY 0.617021 (-2000 3700);
PAINT SKYBLUE (-2000 3700);
FORCEPROP 0 LAST ROOM VDDQ_KLM_PWR_VR
J 0
(-2000 4100);
DISPLAY 1.021277 (-2000 4100);
PAINT ORANGE (-2000 4100);
DISPLAY INVISIBLE (-2000 4100);
FORCEPROP 1 LAST PATH I82
J 0
(-2000 4050);
DISPLAY 0.978723 (-2000 4050);
PAINT WHITE (-2000 4050);
DISPLAY INVISIBLE (-2000 4050);
FORCEPROP 2 LAST CDS_LIB mstr_discrete
J 0
(-2050 3900);
PAINT MONO (-2050 3900);
DISPLAY INVISIBLE (-2050 3900);
FORCEPROP 0 LAST SEC 1
J 0
(-2000 4000);
DISPLAY 0.680851 (-2000 4000);
PAINT MONO (-2000 4000);
DISPLAY INVISIBLE (-2000 4000);
FORCEPROP 2 LAST SEC_TYPE 0402LF
J 0
(-2000 4100);
DISPLAY 1.021277 (-2000 4100);
PAINT ORANGE (-2000 4100);
DISPLAY INVISIBLE (-2000 4100);
FORCEADD GND..1
(-2050 3700);
FORCEPROP 3 LASTPIN (-2050 3750) SIG_NAME GND\g
J 0
(-2040 3760);
DISPLAY 0.659574 (-2040 3760);
PAINT MONO (-2040 3760);
DISPLAY INVISIBLE (-2040 3760);
FORCEPROP 1 LAST HDL_POWER GND
J 0
(-2050 3850);
DISPLAY 1.170213 (-2050 3850);
PAINT GREEN (-2050 3850);
DISPLAY INVISIBLE (-2050 3850);
FORCEPROP 1 LAST BODY_TYPE PLUMBING
J 0
(-2095 3657);
DISPLAY 0.340426 (-2095 3657);
PAINT GREEN (-2095 3657);
DISPLAY INVISIBLE (-2095 3657);
FORCEPROP 1 LAST SIZE 1B
J 0
(-1975 3650);
DISPLAY 1.170213 (-1975 3650);
PAINT AQUA (-1975 3650);
DISPLAY INVISIBLE (-1975 3650);
FORCEPROP 1 LAST VOLTAGE 0
J 0
(-2050 3700);
PAINT SKYBLUE (-2050 3700);
DISPLAY INVISIBLE (-2050 3700);
FORCEPROP 2 LAST ROOM VDDQ_KLM_PWR_VR
J 0
(-2625 3775);
DISPLAY 1.361702 (-2625 3775);
PAINT ORANGE (-2625 3775);
DISPLAY INVISIBLE (-2625 3775);
FORCEPROP 1 LAST PATH I83
J 0
(-1975 3700);
DISPLAY 0.872340 (-1975 3700);
PAINT AQUA (-1975 3700);
DISPLAY INVISIBLE (-1975 3700);
FORCEPROP 2 LAST CDS_LIB mstr_symbols
J 0
(-2050 3700);
PAINT MONO (-2050 3700);
DISPLAY INVISIBLE (-2050 3700);
FORCEADD GND..1
(-2225 2975);
FORCEPROP 3 LASTPIN (-2225 3025) SIG_NAME GND\g
J 0
(-2215 3035);
DISPLAY 0.659574 (-2215 3035);
PAINT MONO (-2215 3035);
DISPLAY INVISIBLE (-2215 3035);
FORCEPROP 1 LAST HDL_POWER GND
J 0
(-2225 3125);
DISPLAY 1.723404 (-2225 3125);
PAINT GREEN (-2225 3125);
DISPLAY INVISIBLE (-2225 3125);
FORCEPROP 1 LAST BODY_TYPE PLUMBING
J 0
(-2270 2932);
DISPLAY 0.340426 (-2270 2932);
PAINT GREEN (-2270 2932);
DISPLAY INVISIBLE (-2270 2932);
FORCEPROP 1 LAST SIZE 1B
J 0
(-2150 2925);
DISPLAY 1.723404 (-2150 2925);
PAINT GREEN (-2150 2925);
DISPLAY INVISIBLE (-2150 2925);
FORCEPROP 1 LAST VOLTAGE 0
J 0
(-2225 2975);
PAINT SKYBLUE (-2225 2975);
DISPLAY INVISIBLE (-2225 2975);
FORCEPROP 2 LAST BOM_COST PROC_VRD_VCCIN_CPU0
J 0
(-2600 3050);
DISPLAY 1.446809 (-2600 3050);
PAINT MONO (-2600 3050);
DISPLAY INVISIBLE (-2600 3050);
FORCEPROP 2 LAST ROOM PVCCIN_CPU0_PWR_VR
J 0
(-2775 3050);
DISPLAY 1.936170 (-2775 3050);
PAINT ORANGE (-2775 3050);
DISPLAY INVISIBLE (-2775 3050);
FORCEPROP 1 LAST PATH I85
J 0
(-2150 2975);
DISPLAY 0.872340 (-2150 2975);
PAINT AQUA (-2150 2975);
DISPLAY INVISIBLE (-2150 2975);
FORCEPROP 2 LAST CDS_LIB mstr_symbols
J 0
(-2225 2975);
PAINT MONO (-2225 2975);
DISPLAY INVISIBLE (-2225 2975);
FORCEADD CAP_A..1
(-3850 775);
FORCEPROP 1 LASTPIN (-3850 675) $PN 2
J 0
(-3840 655);
DISPLAY 0.787234 (-3840 655);
PAINT ORANGE (-3840 655);
FORCEPROP 1 LAST VALUE 0.1UF
J 0
(-3800 825);
DISPLAY 0.617021 (-3800 825);
PAINT SKYBLUE (-3800 825);
FORCEPROP 1 LAST MATERIAL X7R
J 0
(-3800 675);
DISPLAY 0.617021 (-3800 675);
PAINT SKYBLUE (-3800 675);
FORCEPROP 1 LAST VOLTAGE 16V
J 0
(-3800 775);
DISPLAY 0.617021 (-3800 775);
PAINT SKYBLUE (-3800 775);
FORCEPROP 1 LAST PACK_TYPE 0402V
J 0
(-3800 575);
DISPLAY 0.617021 (-3800 575);
PAINT SKYBLUE (-3800 575);
FORCEPROP 0 LAST POP NOPOP
J 0
(-3806 509);
DISPLAY 1.021277 (-3806 509);
PAINT RED (-3806 509);
FORCEPROP 1 LAST PART_NUMBER A36096-030
J 0
(-3800 625);
DISPLAY 0.617021 (-3800 625);
PAINT BLUE (-3800 625);
FORCEPROP 1 LAST TOLERANCE 10%
J 0
(-3800 725);
DISPLAY 0.617021 (-3800 725);
PAINT SKYBLUE (-3800 725);
FORCEPROP 1 LAST LOCATION CT21
J 0
(-3950 825);
DISPLAY 0.617021 (-3950 825);
PAINT AQUA (-3950 825);
FORCEPROP 1 LASTPIN (-3850 875) $PN 1
J 0
(-3840 855);
DISPLAY 0.787234 (-3840 855);
PAINT ORANGE (-3840 855);
FORCEPROP 2 LAST CDS_LIB dev_discrete
J 0
(-3850 775);
PAINT MONO (-3850 775);
DISPLAY INVISIBLE (-3850 775);
FORCEPROP 1 LAST PATH I87
J 0
(-3800 925);
DISPLAY 0.978723 (-3800 925);
PAINT WHITE (-3800 925);
DISPLAY INVISIBLE (-3800 925);
FORCEPROP 2 LAST ROOM PVCCIN_CPU0_PWR_VR
J 0
(-3800 925);
DISPLAY 1.361702 (-3800 925);
PAINT ORANGE (-3800 925);
DISPLAY INVISIBLE (-3800 925);
FORCEPROP 0 LAST SEC 1
J 0
(-3800 875);
DISPLAY 0.680851 (-3800 875);
PAINT MONO (-3800 875);
DISPLAY INVISIBLE (-3800 875);
FORCEPROP 2 LAST SEC_TYPE 0402V
J 0
(-3800 975);
DISPLAY 1.021277 (-3800 975);
PAINT ORANGE (-3800 975);
DISPLAY INVISIBLE (-3800 975);
FORCEADD GND..1
(-3850 525);
FORCEPROP 3 LASTPIN (-3850 575) SIG_NAME GND\g
J 0
(-3840 585);
DISPLAY 0.659574 (-3840 585);
PAINT MONO (-3840 585);
DISPLAY INVISIBLE (-3840 585);
FORCEPROP 1 LAST HDL_POWER GND
J 0
(-3850 675);
DISPLAY 1.723404 (-3850 675);
PAINT GREEN (-3850 675);
DISPLAY INVISIBLE (-3850 675);
FORCEPROP 1 LAST BODY_TYPE PLUMBING
J 0
(-3895 482);
DISPLAY 0.340426 (-3895 482);
PAINT GREEN (-3895 482);
DISPLAY INVISIBLE (-3895 482);
FORCEPROP 2 LAST CDS_LIB mstr_symbols
J 0
(-3850 525);
PAINT MONO (-3850 525);
DISPLAY INVISIBLE (-3850 525);
FORCEPROP 1 LAST PATH I88
J 0
(-3775 525);
DISPLAY 0.872340 (-3775 525);
PAINT AQUA (-3775 525);
DISPLAY INVISIBLE (-3775 525);
FORCEPROP 1 LAST VOLTAGE 0
J 0
(-3850 525);
PAINT SKYBLUE (-3850 525);
DISPLAY INVISIBLE (-3850 525);
FORCEPROP 1 LAST SIZE 1B
J 0
(-3775 475);
DISPLAY 1.723404 (-3775 475);
PAINT GREEN (-3775 475);
DISPLAY INVISIBLE (-3775 475);
FORCEPROP 2 LAST BOM_COST PROC_VRD_VCCIN_CPU0
J 0
(-4225 600);
DISPLAY 1.446809 (-4225 600);
PAINT MONO (-4225 600);
DISPLAY INVISIBLE (-4225 600);
FORCEPROP 2 LAST ROOM PVCCIN_CPU0_PWR_VR
J 0
(-4400 600);
DISPLAY 1.936170 (-4400 600);
PAINT ORANGE (-4400 600);
DISPLAY INVISIBLE (-4400 600);
FORCEADD CAP_A..1
(-800 3400);
FORCEPROP 1 LASTPIN (-800 3300) $PN 2
J 0
(-790 3280);
DISPLAY 0.617021 (-790 3280);
PAINT GREEN (-790 3280);
FORCEPROP 1 LASTPIN (-800 3500) $PN 1
J 0
(-790 3480);
DISPLAY 0.617021 (-790 3480);
PAINT GREEN (-790 3480);
FORCEPROP 1 LAST LOCATION C1D14
J 0
(-750 3550);
DISPLAY 0.617021 (-750 3550);
PAINT AQUA (-750 3550);
FORCEPROP 1 LAST VALUE 22.0UF
J 0
(-750 3500);
DISPLAY 0.617021 (-750 3500);
PAINT SKYBLUE (-750 3500);
FORCEPROP 1 LAST VOLTAGE 4V
J 0
(-750 3450);
DISPLAY 0.617021 (-750 3450);
PAINT SKYBLUE (-750 3450);
FORCEPROP 1 LAST TOLERANCE 20%
J 0
(-750 3400);
DISPLAY 0.617021 (-750 3400);
PAINT SKYBLUE (-750 3400);
FORCEPROP 1 LAST PACK_TYPE 0603V
J 0
(-750 3250);
DISPLAY 0.617021 (-750 3250);
PAINT SKYBLUE (-750 3250);
FORCEPROP 1 LAST PART_NUMBER E15431-004
J 0
(-750 3300);
DISPLAY 0.617021 (-750 3300);
PAINT BLUE (-750 3300);
FORCEPROP 1 LAST MATERIAL X6S
J 0
(-750 3350);
DISPLAY 0.617021 (-750 3350);
PAINT SKYBLUE (-750 3350);
FORCEPROP 0 LAST GROUP PWR_MLCC_CAP
J 0
(-744 3187);
DISPLAY 0.638298 (-744 3187);
PAINT BROWN (-744 3187);
DISPLAY BOTH (-744 3187);
FORCEPROP 2 LAST CDS_LIB dev_discrete
J 0
(-800 3400);
PAINT ORANGE (-800 3400);
DISPLAY INVISIBLE (-800 3400);
FORCEPROP 2 LAST CDS_LOCATION C1D14
J 0
(-750 3500);
DISPLAY 0.617021 (-750 3500);
PAINT AQUA (-750 3500);
DISPLAY INVISIBLE (-750 3500);
FORCEPROP 2 LAST ROOM PVCCIN_CPU1_PWR_VR
J 0
(-750 3550);
DISPLAY 1.446809 (-750 3550);
PAINT MONO (-750 3550);
DISPLAY INVISIBLE (-750 3550);
FORCEPROP 1 LAST PATH I9
J 0
(-750 3550);
DISPLAY 0.978723 (-750 3550);
PAINT WHITE (-750 3550);
DISPLAY INVISIBLE (-750 3550);
FORCEPROP 2 LAST CDS_SEC 1
J 0
(-750 3550);
PAINT ORANGE (-750 3550);
DISPLAY INVISIBLE (-750 3550);
FORCEPROP 2 LAST BOM_COST PROC_VRD_VCCIN_CPU0
J 0
(-750 3550);
DISPLAY 1.446809 (-750 3550);
PAINT MONO (-750 3550);
DISPLAY INVISIBLE (-750 3550);
FORCEPROP 2 LAST SEC 1
J 0
(-750 3600);
DISPLAY 1.936170 (-750 3600);
PAINT MONO (-750 3600);
DISPLAY INVISIBLE (-750 3600);
FORCEPROP 2 LAST SEC_TYPE 0603V
J 0
(-750 3600);
DISPLAY 1.936170 (-750 3600);
PAINT MONO (-750 3600);
DISPLAY INVISIBLE (-750 3600);
FORCEADD CAP..1
(-2000 1300);
FORCEPROP 0 LAST POP NOPOP
J 0
(-1975 1400);
DISPLAY 1.021277 (-1975 1400);
PAINT RED (-1975 1400);
FORCEPROP 1 LASTPIN (-2000 1400) $PN 1
J 0
(-1990 1355);
DISPLAY 0.787234 (-1990 1355);
PAINT ORANGE (-1990 1355);
FORCEPROP 1 LAST VALUE 1000PF
J 0
(-1950 1350);
DISPLAY 0.617021 (-1950 1350);
PAINT SKYBLUE (-1950 1350);
FORCEPROP 1 LASTPIN (-2000 1200) $PN 2
J 0
(-1990 1180);
DISPLAY 0.787234 (-1990 1180);
PAINT ORANGE (-1990 1180);
FORCEPROP 1 LAST LOCATION CT19
J 0
(-2150 1300);
DISPLAY 0.617021 (-2150 1300);
PAINT AQUA (-2150 1300);
FORCEPROP 1 LAST VOLTAGE 50V
J 0
(-1950 1300);
DISPLAY 0.617021 (-1950 1300);
PAINT SKYBLUE (-1950 1300);
FORCEPROP 1 LAST TOLERANCE 10%
J 0
(-1950 1250);
DISPLAY 0.617021 (-1950 1250);
PAINT SKYBLUE (-1950 1250);
FORCEPROP 1 LAST MATERIAL X7R
J 0
(-1950 1200);
DISPLAY 0.617021 (-1950 1200);
PAINT SKYBLUE (-1950 1200);
FORCEPROP 1 LAST PART_NUMBER A36096-046
J 0
(-1950 1150);
DISPLAY 0.617021 (-1950 1150);
PAINT BLUE (-1950 1150);
FORCEPROP 1 LAST PACK_TYPE 0402LF
J 0
(-1950 1100);
DISPLAY 0.617021 (-1950 1100);
PAINT SKYBLUE (-1950 1100);
FORCEPROP 2 LAST CDS_LIB mstr_discrete
J 0
(-2000 1300);
PAINT MONO (-2000 1300);
DISPLAY INVISIBLE (-2000 1300);
FORCEPROP 1 LAST PATH I90
J 0
(-1950 1450);
DISPLAY 0.978723 (-1950 1450);
PAINT WHITE (-1950 1450);
DISPLAY INVISIBLE (-1950 1450);
FORCEPROP 0 LAST ROOM VDDQ_KLM_PWR_VR
J 0
(-1950 1500);
DISPLAY 1.021277 (-1950 1500);
PAINT ORANGE (-1950 1500);
DISPLAY INVISIBLE (-1950 1500);
FORCEPROP 0 LAST SEC 1
J 0
(-1975 1450);
DISPLAY 0.680851 (-1975 1450);
PAINT MONO (-1975 1450);
DISPLAY INVISIBLE (-1975 1450);
FORCEPROP 2 LAST SEC_TYPE 0402LF
J 0
(-1950 1500);
DISPLAY 1.021277 (-1950 1500);
PAINT ORANGE (-1950 1500);
DISPLAY INVISIBLE (-1950 1500);
FORCEADD GND..1
(-2000 1100);
FORCEPROP 3 LASTPIN (-2000 1150) SIG_NAME GND\g
J 0
(-1990 1160);
DISPLAY 0.659574 (-1990 1160);
PAINT MONO (-1990 1160);
DISPLAY INVISIBLE (-1990 1160);
FORCEPROP 1 LAST HDL_POWER GND
J 0
(-2000 1250);
DISPLAY 1.170213 (-2000 1250);
PAINT GREEN (-2000 1250);
DISPLAY INVISIBLE (-2000 1250);
FORCEPROP 1 LAST BODY_TYPE PLUMBING
J 0
(-2045 1057);
DISPLAY 0.340426 (-2045 1057);
PAINT GREEN (-2045 1057);
DISPLAY INVISIBLE (-2045 1057);
FORCEPROP 2 LAST CDS_LIB mstr_symbols
J 0
(-2000 1100);
PAINT MONO (-2000 1100);
DISPLAY INVISIBLE (-2000 1100);
FORCEPROP 1 LAST PATH I91
J 0
(-1925 1100);
DISPLAY 0.872340 (-1925 1100);
PAINT AQUA (-1925 1100);
DISPLAY INVISIBLE (-1925 1100);
FORCEPROP 2 LAST ROOM VDDQ_KLM_PWR_VR
J 0
(-2575 1175);
DISPLAY 1.361702 (-2575 1175);
PAINT ORANGE (-2575 1175);
DISPLAY INVISIBLE (-2575 1175);
FORCEPROP 1 LAST VOLTAGE 0
J 0
(-2000 1100);
PAINT SKYBLUE (-2000 1100);
DISPLAY INVISIBLE (-2000 1100);
FORCEPROP 1 LAST SIZE 1B
J 0
(-1925 1050);
DISPLAY 1.170213 (-1925 1050);
PAINT AQUA (-1925 1050);
DISPLAY INVISIBLE (-1925 1050);
FORCEADD GND..1
(-2075 375);
FORCEPROP 3 LASTPIN (-2075 425) SIG_NAME GND\g
J 0
(-2065 435);
DISPLAY 0.659574 (-2065 435);
PAINT MONO (-2065 435);
DISPLAY INVISIBLE (-2065 435);
FORCEPROP 2 LAST CDS_LIB mstr_symbols
J 0
(-2075 375);
PAINT MONO (-2075 375);
DISPLAY INVISIBLE (-2075 375);
FORCEPROP 1 LAST PATH I93
J 0
(-2000 375);
DISPLAY 0.872340 (-2000 375);
PAINT AQUA (-2000 375);
DISPLAY INVISIBLE (-2000 375);
FORCEPROP 1 LAST SIZE 1B
J 0
(-2000 325);
DISPLAY 1.723404 (-2000 325);
PAINT GREEN (-2000 325);
DISPLAY INVISIBLE (-2000 325);
FORCEPROP 1 LAST VOLTAGE 0
J 0
(-2075 375);
PAINT SKYBLUE (-2075 375);
DISPLAY INVISIBLE (-2075 375);
FORCEPROP 2 LAST BOM_COST PROC_VRD_VCCIN_CPU0
J 0
(-2450 450);
DISPLAY 1.446809 (-2450 450);
PAINT MONO (-2450 450);
DISPLAY INVISIBLE (-2450 450);
FORCEPROP 2 LAST ROOM PVCCIN_CPU0_PWR_VR
J 0
(-2625 450);
DISPLAY 1.936170 (-2625 450);
PAINT ORANGE (-2625 450);
DISPLAY INVISIBLE (-2625 450);
FORCEPROP 1 LAST BODY_TYPE PLUMBING
J 0
(-2120 332);
DISPLAY 0.340426 (-2120 332);
PAINT GREEN (-2120 332);
DISPLAY INVISIBLE (-2120 332);
FORCEPROP 1 LAST HDL_POWER GND
J 0
(-2075 525);
DISPLAY 1.723404 (-2075 525);
PAINT GREEN (-2075 525);
DISPLAY INVISIBLE (-2075 525);
FORCEADD INTEL_CORP_BPAGE..1
(0 0);
FORCEPROP 1 LAST CDS_CON_LAST_MODIFIED Fri Jun 16 17:49:15 2017
J 0
(-1425 325);
PAINT ORANGE (-1425 325);
DISPLAY INVISIBLE (-1425 325);
FORCEPROP 1 LAST CUSTOM_TXT_CDS <CURRENT_DESIGN_SHEET> OF <TOTAL_DESIGN_SHEETS>
J 0
(-500 25);
PAINT ORANGE (-500 25);
FORCEPROP 2 LAST CUSTOM_TXT_CDS <XR_PAGE_TITLE>
J 0
(-7890 5250);
DISPLAY 0.638298 (-7890 5250);
PAINT PINK (-7890 5250);
DISPLAY INVISIBLE (-7890 5250);
FORCEPROP 2 LAST CUSTOM_TXT_CDS <CON_LAST_MODIFIED>
J 0
(-4000 100);
PAINT ORANGE (-4000 100);
FORCEPROP 1 LAST SCH_TITLE VCCIN CPU1 (3 OF 4)
J 0
(-7950 50);
DISPLAY 1.212766 (-7950 50);
PAINT ORANGE (-7950 50);
FORCEPROP 1 LAST COMMENT_BODY TRUE
J 0
(12 12);
DISPLAY 0.468085 (12 12);
PAINT GREEN (12 12);
DISPLAY INVISIBLE (12 12);
FORCEPROP 2 LAST CDS_LIB mstr_symbols
J 0
(0 0);
PAINT MONO (0 0);
DISPLAY INVISIBLE (0 0);
FORCEPROP 2 LAST PAGE_BORDER TRUE
J 0
(-7890 5250);
DISPLAY 0.638298 (-7890 5250);
PAINT PINK (-7890 5250);
DISPLAY INVISIBLE (-7890 5250);
FORCEPROP 2 LAST CDS_XR_PAGE_TITLE CR-208 : @BASEBOARD_FAB2_LIB.BASEBOARD_FAB2(SCH_1):PAGE208
J 0
(-7890 5250);
DISPLAY 0.638298 (-7890 5250);
PAINT PINK (-7890 5250);
DISPLAY INVISIBLE (-7890 5250);
FORCEADD DNS..2
(-695 4070);
PAINT RED (-695 4070);
FORCEPROP 1 LAST COMMENT_BODY TRUE
R 1
J 0
(-620 3845);
DISPLAY 0.872340 (-620 3845);
PAINT GREEN (-620 3845);
DISPLAY INVISIBLE (-620 3845);
FORCEPROP 2 LAST CDS_LIB mstr_misc
J 0
(-695 4070);
PAINT ORANGE (-695 4070);
DISPLAY INVISIBLE (-695 4070);
FORCEADD DNS..2
(-620 1445);
PAINT RED (-620 1445);
FORCEPROP 1 LAST COMMENT_BODY TRUE
R 1
J 0
(-545 1220);
DISPLAY 0.872340 (-545 1220);
PAINT GREEN (-545 1220);
DISPLAY INVISIBLE (-545 1220);
FORCEPROP 2 LAST CDS_LIB mstr_misc
J 0
(-620 1445);
PAINT ORANGE (-620 1445);
DISPLAY INVISIBLE (-620 1445);
WIRE 16 -1 (-400 3125)(-400 3150);
WIRE 16 -1 (-400 3150)(-800 3150);
WIRE 16 -1 (-400 3300)(-400 3150);
WIRE 16 -1 (-800 3300)(-800 3150);
WIRE 16 -1 (-1000 2375)(-1000 2325);
WIRE 16 -1 (-1000 2375)(-1450 2375);
WIRE 16 -1 (-1000 2475)(-1000 2375);
WIRE 16 -1 (-1925 2375)(-1450 2375);
WIRE 16 -1 (-1450 2550)(-1450 2375);
WIRE 16 -1 (-1925 2375)(-2375 2375);
WIRE 16 -1 (-1925 2550)(-1925 2375);
WIRE 16 -1 (-2375 2375)(-2825 2375);
WIRE 16 -1 (-2375 2550)(-2375 2375);
WIRE 16 -1 (-2825 2375)(-3275 2375);
WIRE 16 -1 (-2825 2550)(-2825 2375);
WIRE 16 -1 (-3275 2375)(-3725 2375);
WIRE 16 -1 (-3275 2550)(-3275 2375);
WIRE 16 -1 (-3725 2375)(-4250 2375);
WIRE 16 -1 (-3725 2550)(-3725 2375);
WIRE 16 -1 (-4250 2550)(-4250 2375);
WIRE 16 -1 (-350 1075)(-350 1025);
WIRE 16 -1 (-350 1025)(-700 1025);
WIRE 16 -1 (-350 900)(-350 1025);
WIRE 16 -1 (-850 1025)(-700 1025);
WIRE 16 -1 (-700 900)(-700 1025);
WIRE 16 -1 (-850 375)(-850 1025);
WIRE 16 -1 (-1125 1025)(-850 1025);
WIRE 16 -1 (-3975 375)(-850 375);
WIRE 16 -1 (-3975 1425)(-3975 375);
WIRE 16 -1 (-3750 1425)(-3975 1425);
WIRE 16 -1 (-350 500)(-350 550);
WIRE 16 -1 (-350 550)(-700 550);
WIRE 16 -1 (-350 700)(-350 550);
WIRE 16 -1 (-700 700)(-700 550);
WIRE 16 -1 (-2600 3225)(-2600 3325);
WIRE 16 -1 (-2600 3325)(-2600 3375);
WIRE 16 -1 (-2600 3325)(-2800 3325);
WIRE 16 -1 (-2600 3375)(-2600 3425);
WIRE 16 -1 (-2600 3375)(-2800 3375);
WIRE 16 -1 (-2600 3425)(-2600 3475);
WIRE 16 -1 (-2600 3425)(-2800 3425);
WIRE 16 -1 (-2800 3475)(-2600 3475);
WIRE 16 -1 (-4250 2800)(-4250 2850);
WIRE 16 -1 (-3725 2800)(-4250 2800);
WIRE 16 -1 (-4250 2800)(-4250 2750);
WIRE 16 -1 (-3275 2800)(-3725 2800);
WIRE 16 -1 (-3725 2750)(-3725 2800);
WIRE 16 -1 (-2825 2800)(-3275 2800);
WIRE 16 -1 (-3275 2750)(-3275 2800);
WIRE 16 -1 (-2375 2800)(-2825 2800);
WIRE 16 -1 (-2825 2750)(-2825 2800);
WIRE 16 -1 (-1925 2800)(-2375 2800);
WIRE 16 -1 (-2375 2750)(-2375 2800);
WIRE 16 -1 (-1925 2800)(-1450 2800);
WIRE 16 -1 (-1925 2750)(-1925 2800);
WIRE 16 -1 (-1000 2800)(-1450 2800);
WIRE 16 -1 (-1450 2750)(-1450 2800);
WIRE 16 -1 (-1000 2675)(-1000 2800);
WIRE 16 -1 (-2575 650)(-2575 725);
WIRE 16 -1 (-2575 775)(-2575 725);
WIRE 16 -1 (-2575 725)(-2750 725);
WIRE 16 -1 (-2575 825)(-2575 775);
WIRE 16 -1 (-2750 775)(-2575 775);
WIRE 16 -1 (-2575 875)(-2575 825);
WIRE 16 -1 (-2750 825)(-2575 825);
WIRE 16 -1 (-2750 875)(-2575 875);
WIRE 16 -1 (-6625 4525)(-6625 4375);
WIRE 16 -1 (-6625 4375)(-6550 4375);
WIRE 16 -1 (-6875 4375)(-6625 4375);
WIRE 16 -1 (-6875 4250)(-6875 4375);
WIRE 16 -1 (-6550 4375)(-6275 4375);
WIRE 16 -1 (-6550 4250)(-6550 4375);
WIRE 16 -1 (-6275 4375)(-6025 4375);
WIRE 16 -1 (-6275 4250)(-6275 4375);
WIRE 16 -1 (-6025 4375)(-5775 4375);
WIRE 16 -1 (-6025 4250)(-6025 4375);
WIRE 16 -1 (-4375 4375)(-5775 4375);
WIRE 16 -1 (-5775 4250)(-5775 4375);
WIRE 16 -1 (-4375 4375)(-4375 4325);
WIRE 16 -1 (-3800 4375)(-4375 4375);
WIRE 16 -1 (-3800 4325)(-4375 4325);
WIRE 16 -1 (-6875 3700)(-6875 3900);
WIRE 16 -1 (-6875 3900)(-6550 3900);
WIRE 16 -1 (-6875 4050)(-6875 3900);
WIRE 16 -1 (-6550 3900)(-6275 3900);
WIRE 16 -1 (-6550 4050)(-6550 3900);
WIRE 16 -1 (-6275 3900)(-6025 3900);
WIRE 16 -1 (-6275 4050)(-6275 3900);
WIRE 16 -1 (-6025 3900)(-5775 3900);
WIRE 16 -1 (-6025 4050)(-6025 3900);
WIRE 16 -1 (-5775 3900)(-5500 3900);
WIRE 16 -1 (-5775 4050)(-5775 3900);
WIRE 16 -1 (-5100 3900)(-5500 3900);
WIRE 16 -1 (-5500 4050)(-5500 3900);
WIRE 16 -1 (-4775 3900)(-5100 3900);
WIRE 16 -1 (-5100 4125)(-5100 3900);
WIRE 16 -1 (-4775 4100)(-4775 3900);
WIRE 16 -1 (-6475 1925)(-6475 1775);
WIRE 16 -1 (-6475 1775)(-6250 1775);
WIRE 16 -1 (-6500 1775)(-6475 1775);
WIRE 16 -1 (-6800 1775)(-6500 1775);
WIRE 16 -1 (-6500 1675)(-6500 1775);
WIRE 16 -1 (-6250 1775)(-5950 1775);
WIRE 16 -1 (-6250 1675)(-6250 1775);
WIRE 16 -1 (-5950 1775)(-4075 1775);
WIRE 16 -1 (-5950 1675)(-5950 1775);
WIRE 16 -1 (-7050 1775)(-6800 1775);
WIRE 16 -1 (-6800 1675)(-6800 1775);
WIRE 16 -1 (-7050 1675)(-7050 1775);
WIRE 16 -1 (-4075 1775)(-4075 1725);
WIRE 16 -1 (-3750 1775)(-4075 1775);
WIRE 16 -1 (-4075 1725)(-3750 1725);
WIRE 16 -1 (-7050 1000)(-7050 1250);
WIRE 16 -1 (-7050 1250)(-6800 1250);
WIRE 16 -1 (-7050 1475)(-7050 1250);
WIRE 16 -1 (-6800 1250)(-6500 1250);
WIRE 16 -1 (-6800 1475)(-6800 1250);
WIRE 16 -1 (-6500 1250)(-6250 1250);
WIRE 16 -1 (-6500 1475)(-6500 1250);
WIRE 16 -1 (-6250 1250)(-5950 1250);
WIRE 16 -1 (-6250 1475)(-6250 1250);
WIRE 16 -1 (-5700 1250)(-5950 1250);
WIRE 16 -1 (-5950 1475)(-5950 1250);
WIRE 16 -1 (-5200 1250)(-5700 1250);
WIRE 16 -1 (-5700 1475)(-5700 1250);
WIRE 16 -1 (-4800 1250)(-5200 1250);
WIRE 16 -1 (-5200 1475)(-5200 1250);
WIRE 16 -1 (-4800 1475)(-4800 1250);
WIRE 16 -1 (-4925 4800)(-4925 4700);
WIRE 16 -1 (-4925 4700)(-5100 4700);
WIRE 16 -1 (-4925 4700)(-4775 4700);
WIRE 16 -1 (-4175 4700)(-4775 4700);
WIRE 16 -1 (-4775 4300)(-4775 4700);
WIRE 16 -1 (-5100 4275)(-5100 4700);
WIRE 16 -1 (-5100 4700)(-5250 4700);
WIRE 16 -1 (-4175 4225)(-4175 4700);
WIRE 16 -1 (-4175 4225)(-4175 4125);
WIRE 16 -1 (-3800 4225)(-4175 4225);
WIRE 16 -1 (-4175 4125)(-3800 4125);
WIRE 16 -1 (-5000 2025)(-5000 2100);
WIRE 16 -1 (-5000 2025)(-5200 2025);
WIRE 16 -1 (-5000 2025)(-4800 2025);
WIRE 16 -1 (-3950 2025)(-4800 2025);
WIRE 16 -1 (-4800 1675)(-4800 2025);
WIRE 16 -1 (-5200 2025)(-5350 2025);
WIRE 16 -1 (-5200 1625)(-5200 2025);
WIRE 16 -1 (-3950 2025)(-3950 1625);
WIRE 16 -1 (-3950 1625)(-3950 1525);
WIRE 16 -1 (-3950 1625)(-3750 1625);
WIRE 16 -1 (-3950 1525)(-3750 1525);
WIRE 16 -1 (-700 3975)(-700 3950);
WIRE 16 -1 (-625 1350)(-625 1275);
WIRE 16 -1 (-3975 3275)(-3975 3175);
WIRE 16 -1 (-400 3625)(-400 3650);
WIRE 16 -1 (-400 3625)(-800 3625);
WIRE 16 -1 (-400 3500)(-400 3625);
WIRE 16 -1 (-1175 3625)(-800 3625);
WIRE 16 -1 (-800 3500)(-800 3625);
WIRE 16 -1 (-1175 2950)(-1175 3625);
WIRE 16 -1 (-1275 3625)(-1175 3625);
WIRE 16 -1 (-4050 2950)(-1175 2950);
WIRE 16 -1 (-4050 4025)(-4050 2950);
WIRE 16 -1 (-3800 4025)(-4050 4025);
WIRE 16 -1 (-2050 3800)(-2050 3750);
WIRE 16 -1 (-2225 3050)(-2225 3025);
WIRE 16 -1 (-3850 675)(-3850 575);
WIRE 16 -1 (-2000 1200)(-2000 1150);
WIRE 16 2175 (-5200 3950)(-4600 3950);
WIRE 16 2175 (-4600 4350)(-4600 3950);
WIRE 16 2175 (-5200 4350)(-5200 3950);
WIRE 16 2175 (-5200 4350)(-4600 4350);
WIRE 16 -1 (-3850 875)(-3850 1075);
WIRE 16 -1 (-3750 1075)(-3850 1075);
WIRE 16 -1 (-3850 1075)(-3850 2125);
WIRE 16 -1 (-900 2125)(-3850 2125);
FORCEPROP 2 LAST SIG_NAME VR_PVCCIN_CPU1_AIREF4
J 2
(-1387 2160);
DISPLAY 0.617021 (-1387 2160);
PAINT ORANGE (-1387 2160);
WIRE 16 2175 (-6325 625)(-5350 625);
WIRE 16 2175 (-5350 1150)(-5350 625);
WIRE 16 2175 (-6325 1150)(-6325 625);
WIRE 16 2175 (-6325 1150)(-5350 1150);
WIRE 16 -1 (-1025 4800)(-3975 4800);
FORCEPROP 2 LAST SIG_NAME VR_PVCCIN_CPU1_AIREF3
J 2
(-1437 4810);
DISPLAY 0.617021 (-1437 4810);
PAINT ORANGE (-1437 4810);
WIRE 16 -1 (-3800 3675)(-3975 3675);
WIRE 16 -1 (-3975 3675)(-3975 4800);
WIRE 16 -1 (-3975 3475)(-3975 3675);
WIRE 16 -1 (-4225 3700)(-4875 3700);
FORCEPROP 2 LAST SIG_NAME VR_PVCCIN_CPU1_PH3_BOOT_R
J 0
(-4740 3710);
DISPLAY 0.617021 (-4740 3710);
PAINT ORANGE (-4740 3710);
FORCEPROP 2 LASTPROP $XRERR UNIQUE?
J 0
(-4980 3710);
DISPLAY 0.638298 (-4980 3710);
PAINT MONO (-4980 3710);
DISPLAY INVISIBLE (-4980 3710);
WIRE 16 -1 (-4225 3575)(-4225 3700);
WIRE 16 -1 (-3800 3575)(-4225 3575);
WIRE 3 2175 (-2275 3650)(-1650 3650);
WIRE 3 2175 (-1650 3650)(-1650 2975);
WIRE 3 2175 (-2275 3650)(-2275 2975);
WIRE 3 2175 (-2275 2975)(-1650 2975);
WIRE 16 -1 (-2750 1025)(-2750 975);
WIRE 16 -1 (-2075 975)(-2075 1025);
WIRE 16 -1 (-2750 1025)(-2075 1025);
FORCEPROP 0 LAST VOLTAGE 5
J 0
(-2075 1100);
DISPLAY 1.021277 (-2075 1100);
PAINT SKYBLUE (-2075 1100);
DISPLAY INVISIBLE (-2075 1100);
FORCEPROP 2 LAST SIG_NAME VR_PVCCIN_CPU1_PHASE4
J 0
(-2715 1035);
DISPLAY 0.617021 (-2715 1035);
PAINT ORANGE (-2715 1035);
FORCEPROP 2 LASTPROP $XRERR UNIQUE?
J 0
(-2955 1035);
DISPLAY 0.638298 (-2955 1035);
PAINT MONO (-2955 1035);
DISPLAY INVISIBLE (-2955 1035);
WIRE 16 -1 (-1425 1025)(-2075 1025);
WIRE 16 -1 (-2800 3625)(-2800 3575);
WIRE 16 -1 (-2800 3625)(-2225 3625);
FORCEPROP 0 LAST VOLTAGE 5
J 0
(-2350 3700);
DISPLAY 1.021277 (-2350 3700);
PAINT SKYBLUE (-2350 3700);
DISPLAY INVISIBLE (-2350 3700);
FORCEPROP 2 LAST SIG_NAME VR_PVCCIN_CPU1_PHASE3
J 0
(-2765 3635);
DISPLAY 0.617021 (-2765 3635);
PAINT ORANGE (-2765 3635);
FORCEPROP 2 LASTPROP $XRERR UNIQUE?
J 0
(-3005 3635);
DISPLAY 0.638298 (-3005 3635);
PAINT MONO (-3005 3635);
DISPLAY INVISIBLE (-3005 3635);
WIRE 16 -1 (-2225 3600)(-2225 3625);
WIRE 16 -1 (-1575 3625)(-2225 3625);
WIRE 16 -1 (-5700 2025)(-5550 2025);
WIRE 16 -1 (-5700 1675)(-5700 1825);
WIRE 16 -1 (-5700 2025)(-5700 1825);
WIRE 16 -1 (-3750 1825)(-5700 1825);
FORCEPROP 0 LAST VOLTAGE 5
J 0
(-4375 1900);
DISPLAY 1.021277 (-4375 1900);
PAINT SKYBLUE (-4375 1900);
DISPLAY INVISIBLE (-4375 1900);
FORCEPROP 2 LAST SIG_NAME VR_PVCCIN_CPU1_PH4_VCIN
J 0
(-4765 1835);
DISPLAY 0.617021 (-4765 1835);
PAINT ORANGE (-4765 1835);
FORCEPROP 2 LASTPROP $XRERR UNIQUE?
J 0
(-5005 1835);
DISPLAY 0.638298 (-5005 1835);
PAINT MONO (-5005 1835);
DISPLAY INVISIBLE (-5005 1835);
WIRE 16 2175 (-5375 1350)(-4550 1350);
WIRE 16 2175 (-4550 1725)(-4550 1350);
WIRE 16 2175 (-5375 1725)(-5375 1350);
WIRE 16 2175 (-5375 1725)(-4550 1725);
WIRE 3 682 (-5150 1400)(-5250 1400);
WIRE 3 682 (-5150 1700)(-5150 1400);
WIRE 3 682 (-5250 1400)(-5250 1700);
WIRE 3 682 (-5250 1700)(-5150 1700);
WIRE 3 2175 (-5625 1875)(-5275 1875);
WIRE 3 2175 (-5275 2125)(-5275 1875);
WIRE 3 2175 (-5625 2125)(-5625 1875);
WIRE 3 2175 (-5625 2125)(-5275 2125);
WIRE 16 -1 (-6600 1175)(-3750 1175);
FORCEPROP 2 LAST SIG_NAME VR_PVCCIN_CPU1_PWM4
J 0
(-6613 1185);
DISPLAY 0.617021 (-6613 1185);
PAINT ORANGE (-6613 1185);
WIRE 3 2175 (-5200 825)(-4700 825);
WIRE 3 2175 (-4700 1150)(-4700 825);
WIRE 3 2175 (-5200 1150)(-5200 825);
WIRE 3 2175 (-5200 1150)(-4700 1150);
WIRE 16 -1 (-5500 4700)(-5450 4700);
WIRE 16 -1 (-5500 4250)(-5500 4425);
WIRE 16 -1 (-5500 4700)(-5500 4425);
WIRE 16 -1 (-5500 4425)(-3800 4425);
FORCEPROP 0 LAST VOLTAGE 5
J 0
(-4400 4500);
DISPLAY 1.021277 (-4400 4500);
PAINT SKYBLUE (-4400 4500);
DISPLAY INVISIBLE (-4400 4500);
FORCEPROP 2 LAST SIG_NAME VR_PVCCIN_CPU1_PH3_VCIN
J 0
(-4965 4435);
DISPLAY 0.617021 (-4965 4435);
PAINT ORANGE (-4965 4435);
FORCEPROP 2 LASTPROP $XRERR UNIQUE?
J 0
(-5205 4435);
DISPLAY 0.638298 (-5205 4435);
PAINT MONO (-5205 4435);
DISPLAY INVISIBLE (-5205 4435);
WIRE 3 682 (-5050 4325)(-5050 4050);
WIRE 3 682 (-5150 4325)(-5050 4325);
WIRE 3 682 (-5050 4050)(-5150 4050);
WIRE 3 682 (-5150 4050)(-5150 4325);
WIRE 3 2175 (-5550 4450)(-5150 4450);
WIRE 3 2175 (-5150 4750)(-5150 4450);
WIRE 3 2175 (-5550 4750)(-5550 4450);
WIRE 3 2175 (-5550 4750)(-5150 4750);
WIRE 16 -1 (-6500 3775)(-3800 3775);
WIRE 16 -1 (-5975 3700)(-5075 3700);
WIRE 16 -1 (-5975 3675)(-5975 3700);
FORCEPROP 2 LAST SIG_NAME VR_PVCCIN_CPU1_PH3_BOOT
J 0
(-5990 3710);
DISPLAY 0.617021 (-5990 3710);
PAINT ORANGE (-5990 3710);
FORCEPROP 2 LASTPROP $XRERR UNIQUE?
J 0
(-6230 3710);
DISPLAY 0.638298 (-6230 3710);
PAINT MONO (-6230 3710);
DISPLAY INVISIBLE (-6230 3710);
WIRE 3 682 (-2700 1575)(-2600 1575);
WIRE 3 2175 (-2175 350)(-1575 350);
WIRE 3 2175 (-1575 1050)(-1575 350);
WIRE 3 2175 (-2175 1050)(-2175 350);
WIRE 3 2175 (-2175 1050)(-1575 1050);
WIRE 16 -1 (-2075 725)(-2075 675);
WIRE 16 -1 (-2075 725)(-2075 775);
WIRE 16 -1 (-2075 725)(-1600 725);
FORCEPROP 2 LAST SIG_NAME VR_PVCCIN_CPU1_PHASE4_RC
J 0
(-2040 735);
DISPLAY 0.510638 (-2040 735);
PAINT ORANGE (-2040 735);
FORCEPROP 2 LASTPROP $XRERR UNIQUE?
J 0
(-1570 725);
DISPLAY 0.638298 (-1570 725);
PAINT MONO (-1570 725);
DISPLAY INVISIBLE (-1570 725);
WIRE 16 -1 (-2225 3350)(-2225 3300);
WIRE 16 -1 (-2225 3400)(-2225 3350);
WIRE 16 -1 (-2225 3350)(-1675 3350);
FORCEPROP 2 LAST SIG_NAME VR_PVCCIN_CPU1_PHASE3_RC
J 0
(-2190 3360);
DISPLAY 0.617021 (-2190 3360);
PAINT ORANGE (-2190 3360);
FORCEPROP 2 LASTPROP $XRERR UNIQUE?
J 0
(-1645 3350);
DISPLAY 0.638298 (-1645 3350);
PAINT MONO (-1645 3350);
DISPLAY INVISIBLE (-1645 3350);
WIRE 3 2175 (-2200 3675)(-1650 3675);
WIRE 3 2175 (-1650 4100)(-1650 3675);
WIRE 3 2175 (-2200 4100)(-2200 3675);
WIRE 3 2175 (-2200 4100)(-1650 4100);
WIRE 3 2175 (-2175 1075)(-1750 1075);
WIRE 3 2175 (-1750 1475)(-1750 1075);
WIRE 3 2175 (-2175 1475)(-2175 1075);
WIRE 3 2175 (-2175 1475)(-1750 1475);
WIRE 16 -1 (-4075 925)(-3750 925);
WIRE 16 -1 (-4075 750)(-4075 925);
WIRE 16 -1 (-5975 750)(-5975 800);
WIRE 16 -1 (-5975 750)(-4075 750);
FORCEPROP 0 LAST VOLTAGE 5
J 0
(-5850 825);
DISPLAY 1.021277 (-5850 825);
PAINT SKYBLUE (-5850 825);
DISPLAY INVISIBLE (-5850 825);
FORCEPROP 2 LAST SIG_NAME VR_PVCCIN_CPU1_PH4_PHASE
J 0
(-5940 760);
DISPLAY 0.617021 (-5940 760);
PAINT ORANGE (-5940 760);
FORCEPROP 2 LASTPROP $XRERR UNIQUE?
J 0
(-6180 760);
DISPLAY 0.638298 (-6180 760);
PAINT MONO (-6180 760);
DISPLAY INVISIBLE (-6180 760);
WIRE 16 -1 (-4075 975)(-3750 975);
WIRE 16 -1 (-4075 1075)(-4075 975);
WIRE 16 -1 (-4875 1075)(-4075 1075);
FORCEPROP 2 LAST SIG_NAME VR_PVCCIN_CPU1_PH4_BOOT_R
J 0
(-4765 1085);
DISPLAY 0.617021 (-4765 1085);
PAINT ORANGE (-4765 1085);
FORCEPROP 2 LASTPROP $XRERR UNIQUE?
J 0
(-5005 1085);
DISPLAY 0.638298 (-5005 1085);
PAINT MONO (-5005 1085);
DISPLAY INVISIBLE (-5005 1085);
WIRE 16 -1 (-4525 1275)(-3750 1275);
FORCEPROP 0 LAST SIG_NAME TP_PVCCIN_CPU1_PH4_GL_0
J 0
(-4510 1285);
DISPLAY 0.617021 (-4510 1285);
PAINT ORANGE (-4510 1285);
FORCEPROP 2 LASTPROP $XRERR UNIQUE?
J 0
(-4765 1275);
DISPLAY 0.638298 (-4765 1275);
PAINT MONO (-4765 1275);
DISPLAY INVISIBLE (-4765 1275);
WIRE 16 -1 (-3800 3525)(-4225 3525);
WIRE 16 -1 (-4225 3525)(-4225 3425);
WIRE 16 -1 (-5975 3475)(-5975 3425);
WIRE 16 -1 (-5975 3425)(-4225 3425);
FORCEPROP 2 LAST SIG_NAME VR_PVCCIN_CPU1_PH3_PHASE
J 0
(-5965 3435);
DISPLAY 0.617021 (-5965 3435);
PAINT ORANGE (-5965 3435);
FORCEPROP 2 LASTPROP $XRERR UNIQUE?
J 0
(-6205 3435);
DISPLAY 0.638298 (-6205 3435);
PAINT MONO (-6205 3435);
DISPLAY INVISIBLE (-6205 3435);
WIRE 16 -1 (-2750 1825)(-875 1825);
FORCEPROP 2 LAST SIG_NAME ISENSE_PVCCIN_CPU1_PH4_IMON
J 0
(-1905 1841);
DISPLAY 0.617021 (-1905 1841);
PAINT ORANGE (-1905 1841);
WIRE 16 -1 (-625 1625)(-625 1550);
WIRE 16 -1 (-2750 1625)(-625 1625);
FORCEPROP 0 LAST SIG_NAME VR_PVCCIN_CPU1_PH4_OCSET
J 0
(-2610 1635);
DISPLAY 0.617021 (-2610 1635);
PAINT ORANGE (-2610 1635);
FORCEPROP 2 LASTPROP $XRERR UNIQUE?
J 0
(-2850 1635);
DISPLAY 0.638298 (-2850 1635);
PAINT MONO (-2850 1635);
DISPLAY INVISIBLE (-2850 1635);
WIRE 3 2175 (-5200 3525)(-4775 3525);
WIRE 3 2175 (-4775 3750)(-4775 3525);
WIRE 3 2175 (-5200 3750)(-5200 3525);
WIRE 3 2175 (-5200 3750)(-4775 3750);
WIRE 16 -1 (-4575 3875)(-3800 3875);
FORCEPROP 0 LAST SIG_NAME TP_PVCCIN_CPU1_PH3_GL_0
J 0
(-4560 3885);
DISPLAY 0.617021 (-4560 3885);
PAINT ORANGE (-4560 3885);
FORCEPROP 2 LASTPROP $XRERR UNIQUE?
J 0
(-4815 3875);
DISPLAY 0.638298 (-4815 3875);
PAINT MONO (-4815 3875);
DISPLAY INVISIBLE (-4815 3875);
WIRE 16 -1 (-3800 3925)(-4575 3925);
FORCEPROP 0 LAST SIG_NAME TP_PVCCIN_CPU1_PH3_GL_1
J 0
(-4560 3935);
DISPLAY 0.617021 (-4560 3935);
PAINT ORANGE (-4560 3935);
FORCEPROP 2 LASTPROP $XRERR UNIQUE?
J 0
(-4815 3925);
DISPLAY 0.638298 (-4815 3925);
PAINT MONO (-4815 3925);
DISPLAY INVISIBLE (-4815 3925);
WIRE 16 2175 (-6275 3750)(-5350 3750);
WIRE 16 2175 (-5350 3750)(-5350 3350);
WIRE 16 2175 (-6275 3750)(-6275 3350);
WIRE 16 2175 (-6275 3350)(-5350 3350);
WIRE 16 -1 (-5975 1000)(-5975 1075);
WIRE 16 -1 (-5075 1075)(-5975 1075);
FORCEPROP 2 LAST SIG_NAME VR_PVCCIN_CPU1_PH4_BOOT
J 0
(-5940 1085);
DISPLAY 0.617021 (-5940 1085);
PAINT ORANGE (-5940 1085);
FORCEPROP 2 LASTPROP $XRERR UNIQUE?
J 0
(-6180 1085);
DISPLAY 0.638298 (-6180 1085);
PAINT MONO (-6180 1085);
DISPLAY INVISIBLE (-6180 1085);
WIRE 3 682 (-2725 4175)(-2625 4175);
WIRE 16 -1 (-2050 4000)(-2050 4050);
WIRE 16 -1 (-2050 4050)(-1575 4050);
WIRE 16 -1 (-2800 4050)(-2800 3925);
WIRE 16 -1 (-2800 4050)(-2050 4050);
FORCEPROP 2 LAST SIG_NAME A_TSENSE_PVCCIN_CPU1
J 0
(-2705 4060);
DISPLAY 0.617021 (-2705 4060);
PAINT ORANGE (-2705 4060);
WIRE 16 -1 (-700 4225)(-700 4175);
WIRE 16 -1 (-2800 4225)(-700 4225);
FORCEPROP 0 LAST SIG_NAME VR_PVCCIN_CPU1_PH3_OCSET
J 0
(-2660 4235);
DISPLAY 0.617021 (-2660 4235);
PAINT ORANGE (-2660 4235);
FORCEPROP 2 LASTPROP $XRERR UNIQUE?
J 0
(-2900 4235);
DISPLAY 0.638298 (-2900 4235);
PAINT MONO (-2900 4235);
DISPLAY INVISIBLE (-2900 4235);
WIRE 16 -1 (-2800 4425)(-950 4425);
FORCEPROP 2 LAST SIG_NAME ISENSE_PVCCIN_CPU1_PH3_IMON
J 0
(-2524 4444);
DISPLAY 0.617021 (-2524 4444);
PAINT ORANGE (-2524 4444);
WIRE 16 -1 (-2000 1400)(-2000 1450);
WIRE 16 -1 (-2000 1450)(-1725 1450);
WIRE 16 -1 (-2750 1450)(-2750 1325);
WIRE 16 -1 (-2750 1450)(-2000 1450);
FORCEPROP 2 LAST SIG_NAME A_TSENSE_PVCCIN_CPU1
J 0
(-2684 1463);
DISPLAY 0.617021 (-2684 1463);
PAINT ORANGE (-2684 1463);
WIRE 16 -1 (-3750 1325)(-4525 1325);
FORCEPROP 0 LAST SIG_NAME TP_PVCCIN_CPU1_PH4_GL_1
J 0
(-4510 1335);
DISPLAY 0.617021 (-4510 1335);
PAINT ORANGE (-4510 1335);
FORCEPROP 2 LASTPROP $XRERR UNIQUE?
J 0
(-4765 1325);
DISPLAY 0.638298 (-4765 1325);
PAINT MONO (-4765 1325);
DISPLAY INVISIBLE (-4765 1325);
DOT 1 (-800 3625);
DOT 1 (-400 3150);
DOT 1 (-2225 3350);
DOT 1 (-3975 3675);
DOT 1 (-1925 2800);
DOT 1 (-6025 3900);
DOT 1 (-5775 4375);
DOT 1 (-4925 4700);
DOT 1 (-4775 4700);
DOT 1 (-3275 2375);
DOT 1 (-1175 3625);
DOT 1 (-5000 2025);
DOT 1 (-3950 1625);
DOT 1 (-2600 3325);
DOT 1 (-2075 1025);
DOT 1 (-2050 4050);
DOT 1 (-6275 3900);
DOT 1 (-7050 1250);
DOT 1 (-350 550);
DOT 1 (-850 1025);
DOT 1 (-400 3625);
DOT 1 (-2575 725);
DOT 1 (-2575 775);
DOT 1 (-3850 1075);
DOT 1 (-5700 1825);
DOT 1 (-2000 1450);
DOT 1 (-5700 1250);
DOT 1 (-6625 4375);
DOT 1 (-4375 4375);
DOT 1 (-4075 1775);
DOT 1 (-3725 2375);
DOT 1 (-3725 2800);
DOT 1 (-2825 2800);
DOT 1 (-2600 3375);
DOT 1 (-2575 825);
DOT 1 (-2375 2800);
DOT 1 (-350 1025);
DOT 1 (-700 1025);
DOT 1 (-1450 2800);
DOT 1 (-1000 2375);
DOT 1 (-2600 3425);
DOT 1 (-2225 3625);
DOT 1 (-6250 1775);
DOT 1 (-5950 1775);
DOT 1 (-6500 1775);
DOT 1 (-6500 1250);
DOT 1 (-6800 1775);
DOT 1 (-6800 1250);
DOT 1 (-6475 1775);
DOT 1 (-5500 4425);
DOT 1 (-5500 3900);
DOT 1 (-5775 3900);
DOT 1 (-6025 4375);
DOT 1 (-6275 4375);
DOT 1 (-6550 4375);
DOT 1 (-6550 3900);
DOT 1 (-6875 3900);
DOT 1 (-5950 1250);
DOT 1 (-6250 1250);
DOT 1 (-2075 725);
DOT 1 (-4175 4225);
DOT 1 (-5100 4700);
DOT 1 (-5100 3900);
DOT 1 (-4800 2025);
DOT 1 (-5200 2025);
DOT 1 (-5200 1250);
DOT 1 (-1450 2375);
DOT 1 (-1925 2375);
DOT 1 (-2825 2375);
DOT 1 (-4250 2800);
DOT 1 (-3275 2800);
DOT 1 (-2375 2375);
FORCENOTE
ROOM=PVCCIN_CPU1_PWR_VR
(-7055 3160) 0;
DISPLAY LEFT (-7055 3160);
DISPLAY 2.446809 (-7055 3160);
PAINT PURPLE (-7055 3160);
FORCENOTE
TP FAB1 CHANGE TO 0 OHM 0107
(-5775 2125) 0;
DISPLAY LEFT (-5775 2125);
DISPLAY 0.638298 (-5775 2125);
PAINT RED (-5775 2125);
FORCENOTE
TDA21470
(-3450 4500) 0;
DISPLAY LEFT (-3450 4500);
DISPLAY 1.021277 (-3450 4500);
PAINT SKYBLUE (-3450 4500);
FORCENOTE
ROOM = PVCCIN_CPU1_DECAP_VR
(-3665 2840) 0;
DISPLAY LEFT (-3665 2840);
DISPLAY 2.446809 (-3665 2840);
PAINT PURPLE (-3665 2840);
FORCENOTE
TDA21470
(-3400 1900) 0;
DISPLAY LEFT (-3400 1900);
DISPLAY 1.021277 (-3400 1900);
PAINT SKYBLUE (-3400 1900);
FORCENOTE
TP FAB1 CHANGE L1D1 PN 0122
(-1700 1150) 0;
DISPLAY LEFT (-1700 1150);
DISPLAY 1.021277 (-1700 1150);
PAINT RED (-1700 1150);
FORCENOTE
TP FAB1 CHANGE L1D2 PN 0122
(-1625 3750) 0;
DISPLAY LEFT (-1625 3750);
DISPLAY 1.021277 (-1625 3750);
PAINT RED (-1625 3750);
FORCENOTE
TP FAB1 CO-LAY WITH TI PARTS 11/16
(-1625 3825) 0;
DISPLAY LEFT (-1625 3825);
DISPLAY 0.851064 (-1625 3825);
PAINT RED (-1625 3825);
FORCENOTE
TP FAB1 CO-LAY WITH TI PARTS 11/16
(-1550 475) 0;
DISPLAY LEFT (-1550 475);
DISPLAY 0.702128 (-1550 475);
PAINT RED (-1550 475);
FORCENOTE
TP FAB1 CHANGE RES TO 1 OHM 0603 0107
(-1550 400) 0;
DISPLAY LEFT (-1550 400);
DISPLAY 0.638298 (-1550 400);
PAINT RED (-1550 400);
FORCENOTE
ROOM=PVCCIN_CPU1_PWR_VR
(-7655 360) 0;
DISPLAY LEFT (-7655 360);
DISPLAY 2.446809 (-7655 360);
PAINT PURPLE (-7655 360);
FORCENOTE
TP FAB1 CO-LAY WITH TI PARTS 11/16
(-5225 625) 0;
DISPLAY LEFT (-5225 625);
DISPLAY 0.851064 (-5225 625);
PAINT RED (-5225 625);
FORCENOTE
TP FAB1 DEL NET 0309
(-2600 4150) 0;
DISPLAY LEFT (-2600 4150);
DISPLAY 1.021277 (-2600 4150);
PAINT RED (-2600 4150);
FORCENOTE
SPOF
(-6180 3250) 0;
DISPLAY LEFT (-6180 3250);
DISPLAY 1.936170 (-6180 3250);
PAINT PURPLE (-6180 3250);
FORCENOTE
SPOF
(-6080 500) 0;
DISPLAY LEFT (-6080 500);
DISPLAY 1.808511 (-6080 500);
PAINT PURPLE (-6080 500);
FORCENOTE
TP FAB1 DEL NET 0309
(-2550 1550) 0;
DISPLAY LEFT (-2550 1550);
DISPLAY 1.021277 (-2550 1550);
PAINT RED (-2550 1550);
FORCENOTE
TP FAB1 CO-LAY WITH TI PARTS 11/16
(-5275 3275) 0;
DISPLAY LEFT (-5275 3275);
DISPLAY 0.851064 (-5275 3275);
PAINT RED (-5275 3275);
FORCENOTE
TP FAB1 ADD NET NAME 12/04
(-1550 675) 0;
DISPLAY LEFT (-1550 675);
DISPLAY 0.553191 (-1550 675);
PAINT RED (-1550 675);
FORCENOTE
TP FAB1 CO-LAY WITH TI PARTS 11/16
(-1725 1225) 0;
DISPLAY LEFT (-1725 1225);
DISPLAY 0.851064 (-1725 1225);
PAINT RED (-1725 1225);
FORCENOTE
TP FAB1 CHANGE TO 0 OHM 0107
(-5600 4775) 0;
DISPLAY LEFT (-5600 4775);
DISPLAY 0.638298 (-5600 4775);
PAINT RED (-5600 4775);
FORCENOTE
TP FAB1 CHANGE PN 0310
(-5150 4375) 0;
DISPLAY LEFT (-5150 4375);
DISPLAY 1.021277 (-5150 4375);
PAINT RED (-5150 4375);
FORCENOTE
PLACE ON TOP
(-5330 3800) 0;
DISPLAY LEFT (-5330 3800);
DISPLAY 1.553191 (-5330 3800);
PAINT PURPLE (-5330 3800);
FORCENOTE
PLACE ON TOP
(-5380 1175) 0;
DISPLAY LEFT (-5380 1175);
DISPLAY 1.553191 (-5380 1175);
PAINT PURPLE (-5380 1175);
FORCENOTE
TP FAB1 CHANGE PN 0310
(-5275 1725) 0;
DISPLAY LEFT (-5275 1725);
DISPLAY 1.021277 (-5275 1725);
PAINT RED (-5275 1725);
FORCENOTE
TP FAB1 CHANGE RES TO 1 OHM 0603 0107
(-1600 2975) 0;
DISPLAY LEFT (-1600 2975);
DISPLAY 0.808511 (-1600 2975);
PAINT RED (-1600 2975);
FORCENOTE
TP FAB1 CO-LAY WITH TI PARTS 11/16
(-1600 3050) 0;
DISPLAY LEFT (-1600 3050);
DISPLAY 0.851064 (-1600 3050);
PAINT RED (-1600 3050);
FORCENOTE
TP FAB1 ADD NET NAME 12/04
(-1600 3125) 0;
DISPLAY LEFT (-1600 3125);
DISPLAY 0.808511 (-1600 3125);
PAINT RED (-1600 3125);
QUIT
